FILE_TYPE = MACRO_DRAWING;
SET COLOR_WIRE YELLOW;
SET COLOR_PROP ORANGE;
SET COLOR_DOT WHITE;
SET COLOR_ARC YELLOW;
SET COLOR_BODY GREEN;
SET COLOR_NOTE PURPLE;
SET PROP_DISPLAY VALUE;
SET PAGE_NUMBER P16;
FORCEADD TP_PIONT..1
R 2
(-13300 8300);
FORCEPROP 1 LAST $LOCATION TP132
J 2
(-13400 8300);
DISPLAY 0.808511 (-13400 8300);
PAINT GREEN (-13400 8300);
FORCEPROP 0 LAST CDS_LOCATION TP132
J 0
(-13400 8350);
DISPLAY 1.021277 (-13400 8350);
DISPLAY INVISIBLE (-13400 8350);
FORCEPROP 0 LAST $SEC 1
J 0
(-13400 8350);
DISPLAY 0.680851 (-13400 8350);
PAINT MONO (-13400 8350);
DISPLAY INVISIBLE (-13400 8350);
FORCEPROP 0 LAST CDS_SEC 1
J 0
(-13400 8350);
DISPLAY 1.021277 (-13400 8350);
DISPLAY INVISIBLE (-13400 8350);
FORCEPROP 0 LASTPIN (-13200 8300) $PN 1
J 0
(-13190 8310);
DISPLAY 0.680851 (-13190 8310);
PAINT MONO (-13190 8310);
FORCEPROP 2 LAST CDS_LIB cls
J 0
(-13300 8300);
DISPLAY INVISIBLE (-13300 8300);
FORCEPROP 1 LAST CDS_LMAN_SYM_OUTLINE -50,50,50,-50
J 2
(-13300 8300);
DISPLAY 0.468085 (-13300 8300);
PAINT GREEN (-13300 8300);
DISPLAY INVISIBLE (-13300 8300);
FORCEPROP 1 LAST JEDEC_TYPE TP010CT020B030_PTH
J 2
(-13176 8400);
DISPLAY 0.000000 (-13176 8400);
PAINT GREEN (-13176 8400);
DISPLAY INVISIBLE (-13176 8400);
FORCEPROP 1 LAST BOM_IGNORE TRUE
J 2
(-13176 8400);
DISPLAY 0.000000 (-13176 8400);
PAINT GREEN (-13176 8400);
DISPLAY INVISIBLE (-13176 8400);
FORCEPROP 1 LAST PATH I1014
J 2
(-13380 8413);
DISPLAY 0.808511 (-13380 8413);
PAINT GREEN (-13380 8413);
DISPLAY INVISIBLE (-13380 8413);
FORCEADD TP_PIONT..1
R 2
(-13300 8200);
FORCEPROP 1 LAST $LOCATION TP133
J 2
(-13400 8200);
DISPLAY 0.808511 (-13400 8200);
PAINT GREEN (-13400 8200);
FORCEPROP 0 LAST CDS_LOCATION TP133
J 0
(-13400 8250);
DISPLAY 1.021277 (-13400 8250);
DISPLAY INVISIBLE (-13400 8250);
FORCEPROP 0 LAST $SEC 1
J 0
(-13400 8250);
DISPLAY 0.680851 (-13400 8250);
PAINT MONO (-13400 8250);
DISPLAY INVISIBLE (-13400 8250);
FORCEPROP 0 LAST CDS_SEC 1
J 0
(-13400 8250);
DISPLAY 1.021277 (-13400 8250);
DISPLAY INVISIBLE (-13400 8250);
FORCEPROP 0 LASTPIN (-13200 8200) $PN 1
J 0
(-13190 8210);
DISPLAY 0.680851 (-13190 8210);
PAINT MONO (-13190 8210);
FORCEPROP 2 LAST CDS_LIB cls
J 0
(-13300 8200);
DISPLAY INVISIBLE (-13300 8200);
FORCEPROP 1 LAST CDS_LMAN_SYM_OUTLINE -50,50,50,-50
J 2
(-13300 8200);
DISPLAY 0.468085 (-13300 8200);
PAINT GREEN (-13300 8200);
DISPLAY INVISIBLE (-13300 8200);
FORCEPROP 1 LAST JEDEC_TYPE TP010CT020B030_PTH
J 2
(-13176 8300);
DISPLAY 0.000000 (-13176 8300);
PAINT GREEN (-13176 8300);
DISPLAY INVISIBLE (-13176 8300);
FORCEPROP 1 LAST BOM_IGNORE TRUE
J 2
(-13176 8300);
DISPLAY 0.000000 (-13176 8300);
PAINT GREEN (-13176 8300);
DISPLAY INVISIBLE (-13176 8300);
FORCEPROP 1 LAST PATH I1015
J 2
(-13380 8313);
DISPLAY 0.808511 (-13380 8313);
PAINT GREEN (-13380 8313);
DISPLAY INVISIBLE (-13380 8313);
FORCEADD TP_PIONT..1
R 2
(-13300 8100);
FORCEPROP 1 LAST $LOCATION TP134
J 2
(-13400 8100);
DISPLAY 0.808511 (-13400 8100);
PAINT GREEN (-13400 8100);
FORCEPROP 0 LAST CDS_LOCATION TP134
J 0
(-13400 8150);
DISPLAY 1.021277 (-13400 8150);
DISPLAY INVISIBLE (-13400 8150);
FORCEPROP 0 LAST $SEC 1
J 0
(-13400 8150);
DISPLAY 0.680851 (-13400 8150);
PAINT MONO (-13400 8150);
DISPLAY INVISIBLE (-13400 8150);
FORCEPROP 0 LAST CDS_SEC 1
J 0
(-13400 8150);
DISPLAY 1.021277 (-13400 8150);
DISPLAY INVISIBLE (-13400 8150);
FORCEPROP 0 LASTPIN (-13200 8100) $PN 1
J 0
(-13190 8110);
DISPLAY 0.680851 (-13190 8110);
PAINT MONO (-13190 8110);
FORCEPROP 1 LAST BOM_IGNORE TRUE
J 2
(-13176 8200);
DISPLAY 0.000000 (-13176 8200);
PAINT GREEN (-13176 8200);
DISPLAY INVISIBLE (-13176 8200);
FORCEPROP 1 LAST JEDEC_TYPE TP010CT020B030_PTH
J 2
(-13176 8200);
DISPLAY 0.000000 (-13176 8200);
PAINT GREEN (-13176 8200);
DISPLAY INVISIBLE (-13176 8200);
FORCEPROP 1 LAST CDS_LMAN_SYM_OUTLINE -50,50,50,-50
J 2
(-13300 8100);
DISPLAY 0.468085 (-13300 8100);
PAINT GREEN (-13300 8100);
DISPLAY INVISIBLE (-13300 8100);
FORCEPROP 2 LAST CDS_LIB cls
J 0
(-13300 8100);
DISPLAY INVISIBLE (-13300 8100);
FORCEPROP 1 LAST PATH I1016
J 2
(-13380 8213);
DISPLAY 0.808511 (-13380 8213);
PAINT GREEN (-13380 8213);
DISPLAY INVISIBLE (-13380 8213);
FORCEADD TP_PIONT..1
R 2
(-13300 8000);
FORCEPROP 1 LAST $LOCATION TP135
J 2
(-13400 8000);
DISPLAY 0.808511 (-13400 8000);
PAINT GREEN (-13400 8000);
FORCEPROP 0 LAST CDS_LOCATION TP135
J 0
(-13400 8050);
DISPLAY 1.021277 (-13400 8050);
DISPLAY INVISIBLE (-13400 8050);
FORCEPROP 0 LAST $SEC 1
J 0
(-13400 8050);
DISPLAY 0.680851 (-13400 8050);
PAINT MONO (-13400 8050);
DISPLAY INVISIBLE (-13400 8050);
FORCEPROP 0 LAST CDS_SEC 1
J 0
(-13400 8050);
DISPLAY 1.021277 (-13400 8050);
DISPLAY INVISIBLE (-13400 8050);
FORCEPROP 0 LASTPIN (-13200 8000) $PN 1
J 0
(-13190 8010);
DISPLAY 0.680851 (-13190 8010);
PAINT MONO (-13190 8010);
FORCEPROP 1 LAST BOM_IGNORE TRUE
J 2
(-13176 8100);
DISPLAY 0.000000 (-13176 8100);
PAINT GREEN (-13176 8100);
DISPLAY INVISIBLE (-13176 8100);
FORCEPROP 1 LAST JEDEC_TYPE TP010CT020B030_PTH
J 2
(-13176 8100);
DISPLAY 0.000000 (-13176 8100);
PAINT GREEN (-13176 8100);
DISPLAY INVISIBLE (-13176 8100);
FORCEPROP 1 LAST CDS_LMAN_SYM_OUTLINE -50,50,50,-50
J 2
(-13300 8000);
DISPLAY 0.468085 (-13300 8000);
PAINT GREEN (-13300 8000);
DISPLAY INVISIBLE (-13300 8000);
FORCEPROP 2 LAST CDS_LIB cls
J 0
(-13300 8000);
DISPLAY INVISIBLE (-13300 8000);
FORCEPROP 1 LAST PATH I1017
J 2
(-13380 8113);
DISPLAY 0.808511 (-13380 8113);
PAINT GREEN (-13380 8113);
DISPLAY INVISIBLE (-13380 8113);
FORCEADD TP_PIONT..1
R 2
(-13300 7900);
FORCEPROP 1 LAST $LOCATION TP136
J 2
(-13400 7900);
DISPLAY 0.808511 (-13400 7900);
PAINT GREEN (-13400 7900);
FORCEPROP 0 LAST CDS_LOCATION TP136
J 0
(-13400 7950);
DISPLAY 1.021277 (-13400 7950);
DISPLAY INVISIBLE (-13400 7950);
FORCEPROP 0 LAST $SEC 1
J 0
(-13400 7950);
DISPLAY 0.680851 (-13400 7950);
PAINT MONO (-13400 7950);
DISPLAY INVISIBLE (-13400 7950);
FORCEPROP 0 LAST CDS_SEC 1
J 0
(-13400 7950);
DISPLAY 1.021277 (-13400 7950);
DISPLAY INVISIBLE (-13400 7950);
FORCEPROP 0 LASTPIN (-13200 7900) $PN 1
J 0
(-13190 7910);
DISPLAY 0.680851 (-13190 7910);
PAINT MONO (-13190 7910);
FORCEPROP 1 LAST BOM_IGNORE TRUE
J 2
(-13176 8000);
DISPLAY 0.000000 (-13176 8000);
PAINT GREEN (-13176 8000);
DISPLAY INVISIBLE (-13176 8000);
FORCEPROP 1 LAST JEDEC_TYPE TP010CT020B030_PTH
J 2
(-13176 8000);
DISPLAY 0.000000 (-13176 8000);
PAINT GREEN (-13176 8000);
DISPLAY INVISIBLE (-13176 8000);
FORCEPROP 1 LAST CDS_LMAN_SYM_OUTLINE -50,50,50,-50
J 2
(-13300 7900);
DISPLAY 0.468085 (-13300 7900);
PAINT GREEN (-13300 7900);
DISPLAY INVISIBLE (-13300 7900);
FORCEPROP 2 LAST CDS_LIB cls
J 0
(-13300 7900);
DISPLAY INVISIBLE (-13300 7900);
FORCEPROP 1 LAST PATH I1018
J 2
(-13380 8013);
DISPLAY 0.808511 (-13380 8013);
PAINT GREEN (-13380 8013);
DISPLAY INVISIBLE (-13380 8013);
FORCEADD TP_PIONT..1
R 2
(-13300 7800);
FORCEPROP 1 LAST $LOCATION TP137
J 2
(-13400 7800);
DISPLAY 0.808511 (-13400 7800);
PAINT GREEN (-13400 7800);
FORCEPROP 0 LAST CDS_LOCATION TP137
J 0
(-13400 7850);
DISPLAY 1.021277 (-13400 7850);
DISPLAY INVISIBLE (-13400 7850);
FORCEPROP 0 LAST $SEC 1
J 0
(-13400 7850);
DISPLAY 0.680851 (-13400 7850);
PAINT MONO (-13400 7850);
DISPLAY INVISIBLE (-13400 7850);
FORCEPROP 0 LAST CDS_SEC 1
J 0
(-13400 7850);
DISPLAY 1.021277 (-13400 7850);
DISPLAY INVISIBLE (-13400 7850);
FORCEPROP 0 LASTPIN (-13200 7800) $PN 1
J 0
(-13190 7810);
DISPLAY 0.680851 (-13190 7810);
PAINT MONO (-13190 7810);
FORCEPROP 1 LAST BOM_IGNORE TRUE
J 2
(-13176 7900);
DISPLAY 0.000000 (-13176 7900);
PAINT GREEN (-13176 7900);
DISPLAY INVISIBLE (-13176 7900);
FORCEPROP 1 LAST JEDEC_TYPE TP010CT020B030_PTH
J 2
(-13176 7900);
DISPLAY 0.000000 (-13176 7900);
PAINT GREEN (-13176 7900);
DISPLAY INVISIBLE (-13176 7900);
FORCEPROP 1 LAST CDS_LMAN_SYM_OUTLINE -50,50,50,-50
J 2
(-13300 7800);
DISPLAY 0.468085 (-13300 7800);
PAINT GREEN (-13300 7800);
DISPLAY INVISIBLE (-13300 7800);
FORCEPROP 2 LAST CDS_LIB cls
J 0
(-13300 7800);
DISPLAY INVISIBLE (-13300 7800);
FORCEPROP 1 LAST PATH I1019
J 2
(-13380 7913);
DISPLAY 0.808511 (-13380 7913);
PAINT GREEN (-13380 7913);
DISPLAY INVISIBLE (-13380 7913);
FORCEADD TP_PIONT..1
R 2
(-13300 7700);
FORCEPROP 1 LAST $LOCATION TP138
J 2
(-13400 7700);
DISPLAY 0.808511 (-13400 7700);
PAINT GREEN (-13400 7700);
FORCEPROP 0 LAST CDS_LOCATION TP138
J 0
(-13400 7750);
DISPLAY 1.021277 (-13400 7750);
DISPLAY INVISIBLE (-13400 7750);
FORCEPROP 0 LAST $SEC 1
J 0
(-13400 7750);
DISPLAY 0.680851 (-13400 7750);
PAINT MONO (-13400 7750);
DISPLAY INVISIBLE (-13400 7750);
FORCEPROP 0 LAST CDS_SEC 1
J 0
(-13400 7750);
DISPLAY 1.021277 (-13400 7750);
DISPLAY INVISIBLE (-13400 7750);
FORCEPROP 0 LASTPIN (-13200 7700) $PN 1
J 0
(-13190 7710);
DISPLAY 0.680851 (-13190 7710);
PAINT MONO (-13190 7710);
FORCEPROP 1 LAST BOM_IGNORE TRUE
J 2
(-13176 7800);
DISPLAY 0.000000 (-13176 7800);
PAINT GREEN (-13176 7800);
DISPLAY INVISIBLE (-13176 7800);
FORCEPROP 1 LAST JEDEC_TYPE TP010CT020B030_PTH
J 2
(-13176 7800);
DISPLAY 0.000000 (-13176 7800);
PAINT GREEN (-13176 7800);
DISPLAY INVISIBLE (-13176 7800);
FORCEPROP 1 LAST CDS_LMAN_SYM_OUTLINE -50,50,50,-50
J 2
(-13300 7700);
DISPLAY 0.468085 (-13300 7700);
PAINT GREEN (-13300 7700);
DISPLAY INVISIBLE (-13300 7700);
FORCEPROP 2 LAST CDS_LIB cls
J 0
(-13300 7700);
DISPLAY INVISIBLE (-13300 7700);
FORCEPROP 1 LAST PATH I1020
J 2
(-13380 7813);
DISPLAY 0.808511 (-13380 7813);
PAINT GREEN (-13380 7813);
DISPLAY INVISIBLE (-13380 7813);
FORCEADD TP_PIONT..1
R 2
(-13300 7600);
FORCEPROP 1 LAST $LOCATION TP139
J 2
(-13400 7600);
DISPLAY 0.808511 (-13400 7600);
PAINT GREEN (-13400 7600);
FORCEPROP 0 LAST CDS_LOCATION TP139
J 0
(-13400 7650);
DISPLAY 1.021277 (-13400 7650);
DISPLAY INVISIBLE (-13400 7650);
FORCEPROP 0 LAST $SEC 1
J 0
(-13400 7650);
DISPLAY 0.680851 (-13400 7650);
PAINT MONO (-13400 7650);
DISPLAY INVISIBLE (-13400 7650);
FORCEPROP 0 LAST CDS_SEC 1
J 0
(-13400 7650);
DISPLAY 1.021277 (-13400 7650);
DISPLAY INVISIBLE (-13400 7650);
FORCEPROP 0 LASTPIN (-13200 7600) $PN 1
J 0
(-13190 7610);
DISPLAY 0.680851 (-13190 7610);
PAINT MONO (-13190 7610);
FORCEPROP 1 LAST BOM_IGNORE TRUE
J 2
(-13176 7700);
DISPLAY 0.000000 (-13176 7700);
PAINT GREEN (-13176 7700);
DISPLAY INVISIBLE (-13176 7700);
FORCEPROP 1 LAST JEDEC_TYPE TP010CT020B030_PTH
J 2
(-13176 7700);
DISPLAY 0.000000 (-13176 7700);
PAINT GREEN (-13176 7700);
DISPLAY INVISIBLE (-13176 7700);
FORCEPROP 1 LAST CDS_LMAN_SYM_OUTLINE -50,50,50,-50
J 2
(-13300 7600);
DISPLAY 0.468085 (-13300 7600);
PAINT GREEN (-13300 7600);
DISPLAY INVISIBLE (-13300 7600);
FORCEPROP 2 LAST CDS_LIB cls
J 0
(-13300 7600);
DISPLAY INVISIBLE (-13300 7600);
FORCEPROP 1 LAST PATH I1021
J 2
(-13380 7713);
DISPLAY 0.808511 (-13380 7713);
PAINT GREEN (-13380 7713);
DISPLAY INVISIBLE (-13380 7713);
FORCEADD TP_PIONT..1
R 2
(-13300 7500);
FORCEPROP 1 LAST $LOCATION TP140
J 2
(-13400 7500);
DISPLAY 0.808511 (-13400 7500);
PAINT GREEN (-13400 7500);
FORCEPROP 0 LAST CDS_LOCATION TP140
J 0
(-13400 7550);
DISPLAY 1.021277 (-13400 7550);
DISPLAY INVISIBLE (-13400 7550);
FORCEPROP 0 LAST $SEC 1
J 0
(-13400 7550);
DISPLAY 0.680851 (-13400 7550);
PAINT MONO (-13400 7550);
DISPLAY INVISIBLE (-13400 7550);
FORCEPROP 0 LAST CDS_SEC 1
J 0
(-13400 7550);
DISPLAY 1.021277 (-13400 7550);
DISPLAY INVISIBLE (-13400 7550);
FORCEPROP 0 LASTPIN (-13200 7500) $PN 1
J 0
(-13190 7510);
DISPLAY 0.680851 (-13190 7510);
PAINT MONO (-13190 7510);
FORCEPROP 1 LAST BOM_IGNORE TRUE
J 2
(-13176 7600);
DISPLAY 0.000000 (-13176 7600);
PAINT GREEN (-13176 7600);
DISPLAY INVISIBLE (-13176 7600);
FORCEPROP 1 LAST JEDEC_TYPE TP010CT020B030_PTH
J 2
(-13176 7600);
DISPLAY 0.000000 (-13176 7600);
PAINT GREEN (-13176 7600);
DISPLAY INVISIBLE (-13176 7600);
FORCEPROP 1 LAST CDS_LMAN_SYM_OUTLINE -50,50,50,-50
J 2
(-13300 7500);
DISPLAY 0.468085 (-13300 7500);
PAINT GREEN (-13300 7500);
DISPLAY INVISIBLE (-13300 7500);
FORCEPROP 2 LAST CDS_LIB cls
J 0
(-13300 7500);
DISPLAY INVISIBLE (-13300 7500);
FORCEPROP 1 LAST PATH I1022
J 2
(-13380 7613);
DISPLAY 0.808511 (-13380 7613);
PAINT GREEN (-13380 7613);
DISPLAY INVISIBLE (-13380 7613);
FORCEADD TP_PIONT..1
R 2
(-13300 7400);
FORCEPROP 1 LAST $LOCATION TP141
J 2
(-13400 7400);
DISPLAY 0.808511 (-13400 7400);
PAINT GREEN (-13400 7400);
FORCEPROP 0 LAST CDS_LOCATION TP141
J 0
(-13400 7450);
DISPLAY 1.021277 (-13400 7450);
DISPLAY INVISIBLE (-13400 7450);
FORCEPROP 0 LAST $SEC 1
J 0
(-13400 7450);
DISPLAY 0.680851 (-13400 7450);
PAINT MONO (-13400 7450);
DISPLAY INVISIBLE (-13400 7450);
FORCEPROP 0 LAST CDS_SEC 1
J 0
(-13400 7450);
DISPLAY 1.021277 (-13400 7450);
DISPLAY INVISIBLE (-13400 7450);
FORCEPROP 0 LASTPIN (-13200 7400) $PN 1
J 0
(-13190 7410);
DISPLAY 0.680851 (-13190 7410);
PAINT MONO (-13190 7410);
FORCEPROP 1 LAST BOM_IGNORE TRUE
J 2
(-13176 7500);
DISPLAY 0.000000 (-13176 7500);
PAINT GREEN (-13176 7500);
DISPLAY INVISIBLE (-13176 7500);
FORCEPROP 1 LAST JEDEC_TYPE TP010CT020B030_PTH
J 2
(-13176 7500);
DISPLAY 0.000000 (-13176 7500);
PAINT GREEN (-13176 7500);
DISPLAY INVISIBLE (-13176 7500);
FORCEPROP 1 LAST CDS_LMAN_SYM_OUTLINE -50,50,50,-50
J 2
(-13300 7400);
DISPLAY 0.468085 (-13300 7400);
PAINT GREEN (-13300 7400);
DISPLAY INVISIBLE (-13300 7400);
FORCEPROP 2 LAST CDS_LIB cls
J 0
(-13300 7400);
DISPLAY INVISIBLE (-13300 7400);
FORCEPROP 1 LAST PATH I1023
J 2
(-13380 7513);
DISPLAY 0.808511 (-13380 7513);
PAINT GREEN (-13380 7513);
DISPLAY INVISIBLE (-13380 7513);
FORCEADD TP_PIONT..1
(-1000 8800);
FORCEPROP 1 LAST $LOCATION TP52
J 0
(-900 8800);
DISPLAY 0.808511 (-900 8800);
PAINT GREEN (-900 8800);
FORCEPROP 0 LAST CDS_LOCATION TP52
J 0
(-900 8850);
DISPLAY 1.021277 (-900 8850);
DISPLAY INVISIBLE (-900 8850);
FORCEPROP 0 LAST $SEC 1
J 0
(-900 8850);
DISPLAY 0.680851 (-900 8850);
PAINT MONO (-900 8850);
DISPLAY INVISIBLE (-900 8850);
FORCEPROP 0 LAST CDS_SEC 1
J 0
(-900 8850);
DISPLAY 1.021277 (-900 8850);
DISPLAY INVISIBLE (-900 8850);
FORCEPROP 0 LASTPIN (-1100 8800) $PN 1
J 2
(-1110 8810);
DISPLAY 0.680851 (-1110 8810);
PAINT MONO (-1110 8810);
FORCEPROP 1 LAST CDS_LMAN_SYM_OUTLINE -50,50,50,-50
J 0
(-1000 8800);
DISPLAY 0.468085 (-1000 8800);
PAINT GREEN (-1000 8800);
DISPLAY INVISIBLE (-1000 8800);
FORCEPROP 2 LAST CDS_LIB cls
J 0
(-1000 8800);
DISPLAY INVISIBLE (-1000 8800);
FORCEPROP 1 LAST PATH I1206
J 0
(-920 8913);
DISPLAY 0.808511 (-920 8913);
PAINT GREEN (-920 8913);
DISPLAY INVISIBLE (-920 8913);
FORCEPROP 1 LAST JEDEC_TYPE TP010CT020B030_PTH
J 0
(-1124 8900);
DISPLAY 0.000000 (-1124 8900);
PAINT GREEN (-1124 8900);
DISPLAY INVISIBLE (-1124 8900);
FORCEPROP 1 LAST BOM_IGNORE TRUE
J 0
(-1124 8900);
DISPLAY 0.000000 (-1124 8900);
PAINT GREEN (-1124 8900);
DISPLAY INVISIBLE (-1124 8900);
FORCEADD VCC..1
(-2000 8900);
FORCEPROP 3 LASTPIN (-1950 8850) SIG_NAME XP12R0V\g
J 0
(-1940 8860);
DISPLAY 0.659574 (-1940 8860);
PAINT MONO (-1940 8860);
DISPLAY INVISIBLE (-1940 8860);
FORCEPROP 1 LAST HDL_POWER XP12R0V
J 1
(-1945 8955);
DISPLAY 1.021277 (-1945 8955);
PAINT GREEN (-1945 8955);
FORCEPROP 0 LAST VOLTAGE 12V
J 0
(-2200 9050);
DISPLAY 1.021277 (-2200 9050);
DISPLAY BOTH (-2200 9050);
FORCEPROP 2 LAST CDS_LIB cls
J 0
(-2000 8900);
DISPLAY INVISIBLE (-2000 8900);
FORCEPROP 1 LAST CDS_LMAN_SYM_OUTLINE -250,250,250,-250
J 0
(-2000 8900);
DISPLAY 0.468085 (-2000 8900);
PAINT GREEN (-2000 8900);
DISPLAY INVISIBLE (-2000 8900);
FORCEPROP 1 LAST BODY_TYPE PLUMBING
J 0
(-2045 8857);
DISPLAY 0.340426 (-2045 8857);
PAINT GREEN (-2045 8857);
DISPLAY INVISIBLE (-2045 8857);
FORCEPROP 1 LAST PATH I1207
J 0
(-1965 8990);
DISPLAY 0.808511 (-1965 8990);
PAINT GREEN (-1965 8990);
DISPLAY INVISIBLE (-1965 8990);
FORCEADD TP_PIONT..1
(-1000 8350);
FORCEPROP 1 LAST $LOCATION TP53
J 0
(-900 8350);
DISPLAY 0.808511 (-900 8350);
PAINT GREEN (-900 8350);
FORCEPROP 0 LAST CDS_LOCATION TP53
J 0
(-900 8400);
DISPLAY 1.021277 (-900 8400);
DISPLAY INVISIBLE (-900 8400);
FORCEPROP 0 LAST $SEC 1
J 0
(-900 8400);
DISPLAY 0.680851 (-900 8400);
PAINT MONO (-900 8400);
DISPLAY INVISIBLE (-900 8400);
FORCEPROP 0 LAST CDS_SEC 1
J 0
(-900 8400);
DISPLAY 1.021277 (-900 8400);
DISPLAY INVISIBLE (-900 8400);
FORCEPROP 0 LASTPIN (-1100 8350) $PN 1
J 2
(-1110 8360);
DISPLAY 0.680851 (-1110 8360);
PAINT MONO (-1110 8360);
FORCEPROP 2 LAST CDS_LIB cls
J 0
(-1000 8350);
DISPLAY INVISIBLE (-1000 8350);
FORCEPROP 1 LAST CDS_LMAN_SYM_OUTLINE -50,50,50,-50
J 0
(-1000 8350);
DISPLAY 0.468085 (-1000 8350);
PAINT GREEN (-1000 8350);
DISPLAY INVISIBLE (-1000 8350);
FORCEPROP 1 LAST BOM_IGNORE TRUE
J 0
(-1124 8450);
DISPLAY 0.000000 (-1124 8450);
PAINT GREEN (-1124 8450);
DISPLAY INVISIBLE (-1124 8450);
FORCEPROP 1 LAST JEDEC_TYPE TP010CT020B030_PTH
J 0
(-1124 8450);
DISPLAY 0.000000 (-1124 8450);
PAINT GREEN (-1124 8450);
DISPLAY INVISIBLE (-1124 8450);
FORCEPROP 1 LAST PATH I1208
J 0
(-920 8463);
DISPLAY 0.808511 (-920 8463);
PAINT GREEN (-920 8463);
DISPLAY INVISIBLE (-920 8463);
FORCEADD VCC..1
(-2000 8450);
FORCEPROP 3 LASTPIN (-1950 8400) SIG_NAME XP3R3V\g
J 0
(-1940 8410);
DISPLAY 0.659574 (-1940 8410);
PAINT MONO (-1940 8410);
DISPLAY INVISIBLE (-1940 8410);
FORCEPROP 1 LAST HDL_POWER XP3R3V
J 1
(-1950 8500);
DISPLAY 1.021277 (-1950 8500);
PAINT GREEN (-1950 8500);
FORCEPROP 0 LAST VOLTAGE 3.3
J 0
(-2200 8600);
DISPLAY 1.021277 (-2200 8600);
DISPLAY BOTH (-2200 8600);
FORCEPROP 2 LAST CDS_LIB cls
J 0
(-2000 8450);
DISPLAY INVISIBLE (-2000 8450);
FORCEPROP 1 LAST CDS_LMAN_SYM_OUTLINE -250,250,250,-250
J 0
(-2000 8450);
DISPLAY 0.468085 (-2000 8450);
PAINT GREEN (-2000 8450);
DISPLAY INVISIBLE (-2000 8450);
FORCEPROP 1 LAST BODY_TYPE PLUMBING
J 0
(-2045 8407);
DISPLAY 0.340426 (-2045 8407);
PAINT GREEN (-2045 8407);
DISPLAY INVISIBLE (-2045 8407);
FORCEPROP 1 LAST PATH I1209
J 0
(-1965 8540);
DISPLAY 0.808511 (-1965 8540);
PAINT GREEN (-1965 8540);
DISPLAY INVISIBLE (-1965 8540);
FORCEADD TP_PIONT..1
(-1000 7900);
FORCEPROP 1 LAST $LOCATION TP54
J 0
(-900 7900);
DISPLAY 0.808511 (-900 7900);
PAINT GREEN (-900 7900);
FORCEPROP 0 LAST CDS_LOCATION TP54
J 0
(-900 7950);
DISPLAY 1.021277 (-900 7950);
DISPLAY INVISIBLE (-900 7950);
FORCEPROP 0 LAST $SEC 1
J 0
(-900 7950);
DISPLAY 0.680851 (-900 7950);
PAINT MONO (-900 7950);
DISPLAY INVISIBLE (-900 7950);
FORCEPROP 0 LAST CDS_SEC 1
J 0
(-900 7950);
DISPLAY 1.021277 (-900 7950);
DISPLAY INVISIBLE (-900 7950);
FORCEPROP 0 LASTPIN (-1100 7900) $PN 1
J 2
(-1110 7910);
DISPLAY 0.680851 (-1110 7910);
PAINT MONO (-1110 7910);
FORCEPROP 2 LAST CDS_LIB cls
J 0
(-1000 7900);
DISPLAY INVISIBLE (-1000 7900);
FORCEPROP 1 LAST CDS_LMAN_SYM_OUTLINE -50,50,50,-50
J 0
(-1000 7900);
DISPLAY 0.468085 (-1000 7900);
PAINT GREEN (-1000 7900);
DISPLAY INVISIBLE (-1000 7900);
FORCEPROP 1 LAST BOM_IGNORE TRUE
J 0
(-1124 8000);
DISPLAY 0.000000 (-1124 8000);
PAINT GREEN (-1124 8000);
DISPLAY INVISIBLE (-1124 8000);
FORCEPROP 1 LAST JEDEC_TYPE TP010CT020B030_PTH
J 0
(-1124 8000);
DISPLAY 0.000000 (-1124 8000);
PAINT GREEN (-1124 8000);
DISPLAY INVISIBLE (-1124 8000);
FORCEPROP 1 LAST PATH I1210
J 0
(-920 8013);
DISPLAY 0.808511 (-920 8013);
PAINT GREEN (-920 8013);
DISPLAY INVISIBLE (-920 8013);
FORCEADD TP_PIONT..1
(-1000 7450);
FORCEPROP 1 LAST $LOCATION TP55
J 0
(-900 7450);
DISPLAY 0.808511 (-900 7450);
PAINT GREEN (-900 7450);
FORCEPROP 0 LAST CDS_LOCATION TP55
J 0
(-900 7500);
DISPLAY 1.021277 (-900 7500);
DISPLAY INVISIBLE (-900 7500);
FORCEPROP 0 LAST $SEC 1
J 0
(-900 7500);
DISPLAY 0.680851 (-900 7500);
PAINT MONO (-900 7500);
DISPLAY INVISIBLE (-900 7500);
FORCEPROP 0 LAST CDS_SEC 1
J 0
(-900 7500);
DISPLAY 1.021277 (-900 7500);
DISPLAY INVISIBLE (-900 7500);
FORCEPROP 0 LASTPIN (-1100 7450) $PN 1
J 2
(-1110 7460);
DISPLAY 0.680851 (-1110 7460);
PAINT MONO (-1110 7460);
FORCEPROP 1 LAST JEDEC_TYPE TP010CT020B030_PTH
J 0
(-1124 7550);
DISPLAY 0.000000 (-1124 7550);
PAINT GREEN (-1124 7550);
DISPLAY INVISIBLE (-1124 7550);
FORCEPROP 1 LAST BOM_IGNORE TRUE
J 0
(-1124 7550);
DISPLAY 0.000000 (-1124 7550);
PAINT GREEN (-1124 7550);
DISPLAY INVISIBLE (-1124 7550);
FORCEPROP 1 LAST CDS_LMAN_SYM_OUTLINE -50,50,50,-50
J 0
(-1000 7450);
DISPLAY 0.468085 (-1000 7450);
PAINT GREEN (-1000 7450);
DISPLAY INVISIBLE (-1000 7450);
FORCEPROP 2 LAST CDS_LIB cls
J 0
(-1000 7450);
DISPLAY INVISIBLE (-1000 7450);
FORCEPROP 1 LAST PATH I1212
J 0
(-920 7563);
DISPLAY 0.808511 (-920 7563);
PAINT GREEN (-920 7563);
DISPLAY INVISIBLE (-920 7563);
FORCEADD TP_PIONT..1
(-1000 7000);
FORCEPROP 1 LAST $LOCATION TP56
J 0
(-900 7000);
DISPLAY 0.808511 (-900 7000);
PAINT GREEN (-900 7000);
FORCEPROP 0 LAST CDS_LOCATION TP56
J 0
(-900 7050);
DISPLAY 1.021277 (-900 7050);
DISPLAY INVISIBLE (-900 7050);
FORCEPROP 0 LAST $SEC 1
J 0
(-900 7050);
DISPLAY 0.680851 (-900 7050);
PAINT MONO (-900 7050);
DISPLAY INVISIBLE (-900 7050);
FORCEPROP 0 LAST CDS_SEC 1
J 0
(-900 7050);
DISPLAY 1.021277 (-900 7050);
DISPLAY INVISIBLE (-900 7050);
FORCEPROP 0 LASTPIN (-1100 7000) $PN 1
J 2
(-1110 7010);
DISPLAY 0.680851 (-1110 7010);
PAINT MONO (-1110 7010);
FORCEPROP 2 LAST CDS_LIB cls
J 0
(-1000 7000);
DISPLAY INVISIBLE (-1000 7000);
FORCEPROP 1 LAST CDS_LMAN_SYM_OUTLINE -50,50,50,-50
J 0
(-1000 7000);
DISPLAY 0.468085 (-1000 7000);
PAINT GREEN (-1000 7000);
DISPLAY INVISIBLE (-1000 7000);
FORCEPROP 1 LAST BOM_IGNORE TRUE
J 0
(-1124 7100);
DISPLAY 0.000000 (-1124 7100);
PAINT GREEN (-1124 7100);
DISPLAY INVISIBLE (-1124 7100);
FORCEPROP 1 LAST JEDEC_TYPE TP010CT020B030_PTH
J 0
(-1124 7100);
DISPLAY 0.000000 (-1124 7100);
PAINT GREEN (-1124 7100);
DISPLAY INVISIBLE (-1124 7100);
FORCEPROP 1 LAST PATH I1215
J 0
(-920 7113);
DISPLAY 0.808511 (-920 7113);
PAINT GREEN (-920 7113);
DISPLAY INVISIBLE (-920 7113);
FORCEADD TP_PIONT..1
(-3300 9150);
FORCEPROP 1 LAST $LOCATION TP57
J 0
(-3200 9150);
DISPLAY 0.808511 (-3200 9150);
PAINT GREEN (-3200 9150);
FORCEPROP 0 LAST CDS_LOCATION TP57
J 0
(-3200 9200);
DISPLAY 1.021277 (-3200 9200);
DISPLAY INVISIBLE (-3200 9200);
FORCEPROP 0 LAST $SEC 1
J 0
(-3200 9200);
DISPLAY 0.680851 (-3200 9200);
PAINT MONO (-3200 9200);
DISPLAY INVISIBLE (-3200 9200);
FORCEPROP 0 LAST CDS_SEC 1
J 0
(-3200 9200);
DISPLAY 1.021277 (-3200 9200);
DISPLAY INVISIBLE (-3200 9200);
FORCEPROP 0 LASTPIN (-3400 9150) $PN 1
J 2
(-3410 9160);
DISPLAY 0.680851 (-3410 9160);
PAINT MONO (-3410 9160);
FORCEPROP 1 LAST PATH I1217
J 0
(-3220 9263);
DISPLAY 0.808511 (-3220 9263);
PAINT GREEN (-3220 9263);
DISPLAY INVISIBLE (-3220 9263);
FORCEPROP 1 LAST JEDEC_TYPE TP010CT020B030_PTH
J 0
(-3424 9250);
DISPLAY 0.000000 (-3424 9250);
PAINT GREEN (-3424 9250);
DISPLAY INVISIBLE (-3424 9250);
FORCEPROP 1 LAST BOM_IGNORE TRUE
J 0
(-3424 9250);
DISPLAY 0.000000 (-3424 9250);
PAINT GREEN (-3424 9250);
DISPLAY INVISIBLE (-3424 9250);
FORCEPROP 1 LAST CDS_LMAN_SYM_OUTLINE -50,50,50,-50
J 0
(-3300 9150);
DISPLAY 0.468085 (-3300 9150);
PAINT GREEN (-3300 9150);
DISPLAY INVISIBLE (-3300 9150);
FORCEPROP 2 LAST CDS_LIB cls
J 0
(-3300 9150);
DISPLAY INVISIBLE (-3300 9150);
FORCEADD TP_PIONT..1
(-3300 8700);
FORCEPROP 1 LAST $LOCATION TP58
J 0
(-3200 8700);
DISPLAY 0.808511 (-3200 8700);
PAINT GREEN (-3200 8700);
FORCEPROP 0 LAST CDS_LOCATION TP58
J 0
(-3200 8750);
DISPLAY 1.021277 (-3200 8750);
DISPLAY INVISIBLE (-3200 8750);
FORCEPROP 0 LAST $SEC 1
J 0
(-3200 8750);
DISPLAY 0.680851 (-3200 8750);
PAINT MONO (-3200 8750);
DISPLAY INVISIBLE (-3200 8750);
FORCEPROP 0 LAST CDS_SEC 1
J 0
(-3200 8750);
DISPLAY 1.021277 (-3200 8750);
DISPLAY INVISIBLE (-3200 8750);
FORCEPROP 0 LASTPIN (-3400 8700) $PN 1
J 2
(-3410 8710);
DISPLAY 0.680851 (-3410 8710);
PAINT MONO (-3410 8710);
FORCEPROP 1 LAST PATH I1219
J 0
(-3220 8813);
DISPLAY 0.808511 (-3220 8813);
PAINT GREEN (-3220 8813);
DISPLAY INVISIBLE (-3220 8813);
FORCEPROP 2 LAST CDS_LIB cls
J 0
(-3300 8700);
DISPLAY INVISIBLE (-3300 8700);
FORCEPROP 1 LAST CDS_LMAN_SYM_OUTLINE -50,50,50,-50
J 0
(-3300 8700);
DISPLAY 0.468085 (-3300 8700);
PAINT GREEN (-3300 8700);
DISPLAY INVISIBLE (-3300 8700);
FORCEPROP 1 LAST BOM_IGNORE TRUE
J 0
(-3424 8800);
DISPLAY 0.000000 (-3424 8800);
PAINT GREEN (-3424 8800);
DISPLAY INVISIBLE (-3424 8800);
FORCEPROP 1 LAST JEDEC_TYPE TP010CT020B030_PTH
J 0
(-3424 8800);
DISPLAY 0.000000 (-3424 8800);
PAINT GREEN (-3424 8800);
DISPLAY INVISIBLE (-3424 8800);
FORCEADD VCC..1
(-2000 8050);
FORCEPROP 3 LASTPIN (-1950 8000) SIG_NAME XP1R0V_FPGA\g
J 0
(-1940 8010);
DISPLAY 0.659574 (-1940 8010);
PAINT MONO (-1940 8010);
DISPLAY INVISIBLE (-1940 8010);
FORCEPROP 1 LAST HDL_POWER XP1R0V_FPGA
J 1
(-1940 8090);
DISPLAY 1.021277 (-1940 8090);
PAINT GREEN (-1940 8090);
FORCEPROP 0 LAST VOLTAGE 1.0V
J 0
(-2250 8150);
DISPLAY 1.021277 (-2250 8150);
DISPLAY BOTH (-2250 8150);
FORCEPROP 1 LAST PATH I1220
J 0
(-1965 8140);
DISPLAY 0.808511 (-1965 8140);
PAINT GREEN (-1965 8140);
DISPLAY INVISIBLE (-1965 8140);
FORCEPROP 1 LAST BODY_TYPE PLUMBING
J 0
(-2045 8007);
DISPLAY 0.340426 (-2045 8007);
PAINT GREEN (-2045 8007);
DISPLAY INVISIBLE (-2045 8007);
FORCEPROP 1 LAST CDS_LMAN_SYM_OUTLINE -250,250,250,-250
J 0
(-2000 8050);
DISPLAY 0.468085 (-2000 8050);
PAINT GREEN (-2000 8050);
DISPLAY INVISIBLE (-2000 8050);
FORCEPROP 2 LAST CDS_LIB cls
J 0
(-2000 8050);
DISPLAY INVISIBLE (-2000 8050);
FORCEADD VCC..1
(-2000 7600);
FORCEPROP 3 LASTPIN (-1950 7550) SIG_NAME XP1R2V_FPGA\g
J 0
(-1940 7560);
DISPLAY 0.659574 (-1940 7560);
PAINT MONO (-1940 7560);
DISPLAY INVISIBLE (-1940 7560);
FORCEPROP 0 LAST VOLTAGE 1.2V
J 0
(-2250 7750);
DISPLAY 1.021277 (-2250 7750);
DISPLAY BOTH (-2250 7750);
FORCEPROP 1 LAST HDL_POWER XP1R2V_FPGA
J 1
(-1945 7655);
DISPLAY 1.021277 (-1945 7655);
PAINT GREEN (-1945 7655);
FORCEPROP 1 LAST PATH I1221
J 0
(-1965 7690);
DISPLAY 0.808511 (-1965 7690);
PAINT GREEN (-1965 7690);
DISPLAY INVISIBLE (-1965 7690);
FORCEPROP 1 LAST BODY_TYPE PLUMBING
J 0
(-2045 7557);
DISPLAY 0.340426 (-2045 7557);
PAINT GREEN (-2045 7557);
DISPLAY INVISIBLE (-2045 7557);
FORCEPROP 1 LAST CDS_LMAN_SYM_OUTLINE -250,250,250,-250
J 0
(-2000 7600);
DISPLAY 0.468085 (-2000 7600);
PAINT GREEN (-2000 7600);
DISPLAY INVISIBLE (-2000 7600);
FORCEPROP 2 LAST CDS_LIB cls
J 0
(-2000 7600);
DISPLAY INVISIBLE (-2000 7600);
FORCEADD VCC..1
(-2000 7150);
FORCEPROP 3 LASTPIN (-1950 7100) SIG_NAME XP1R8V_FPGA\g
J 0
(-1940 7110);
DISPLAY 0.659574 (-1940 7110);
PAINT MONO (-1940 7110);
DISPLAY INVISIBLE (-1940 7110);
FORCEPROP 1 LAST HDL_POWER XP1R8V_FPGA
J 1
(-1945 7205);
DISPLAY 1.021277 (-1945 7205);
PAINT GREEN (-1945 7205);
FORCEPROP 0 LAST VOLTAGE 1.8V
J 0
(-2200 7300);
DISPLAY 1.021277 (-2200 7300);
DISPLAY BOTH (-2200 7300);
FORCEPROP 1 LAST PATH I1222
J 0
(-1965 7240);
DISPLAY 0.808511 (-1965 7240);
PAINT GREEN (-1965 7240);
DISPLAY INVISIBLE (-1965 7240);
FORCEPROP 1 LAST BODY_TYPE PLUMBING
J 0
(-2045 7107);
DISPLAY 0.340426 (-2045 7107);
PAINT GREEN (-2045 7107);
DISPLAY INVISIBLE (-2045 7107);
FORCEPROP 1 LAST CDS_LMAN_SYM_OUTLINE -250,250,250,-250
J 0
(-2000 7150);
DISPLAY 0.468085 (-2000 7150);
PAINT GREEN (-2000 7150);
DISPLAY INVISIBLE (-2000 7150);
FORCEPROP 2 LAST CDS_LIB cls
J 0
(-2000 7150);
DISPLAY INVISIBLE (-2000 7150);
FORCEADD VCC..1
(-4300 9300);
FORCEPROP 3 LASTPIN (-4250 9250) SIG_NAME XP2R5V_FPGA\g
J 0
(-4240 9260);
DISPLAY 0.659574 (-4240 9260);
PAINT MONO (-4240 9260);
DISPLAY INVISIBLE (-4240 9260);
FORCEPROP 1 LAST HDL_POWER XP2R5V_FPGA
J 1
(-4245 9355);
DISPLAY 1.021277 (-4245 9355);
PAINT GREEN (-4245 9355);
FORCEPROP 0 LAST VOLTAGE 2.5V
J 0
(-4550 9450);
DISPLAY 1.021277 (-4550 9450);
DISPLAY BOTH (-4550 9450);
FORCEPROP 2 LAST CDS_LIB cls
J 0
(-4300 9300);
DISPLAY INVISIBLE (-4300 9300);
FORCEPROP 1 LAST CDS_LMAN_SYM_OUTLINE -250,250,250,-250
J 0
(-4300 9300);
DISPLAY 0.468085 (-4300 9300);
PAINT GREEN (-4300 9300);
DISPLAY INVISIBLE (-4300 9300);
FORCEPROP 1 LAST BODY_TYPE PLUMBING
J 0
(-4345 9257);
DISPLAY 0.340426 (-4345 9257);
PAINT GREEN (-4345 9257);
DISPLAY INVISIBLE (-4345 9257);
FORCEPROP 1 LAST PATH I1223
J 0
(-4265 9390);
DISPLAY 0.808511 (-4265 9390);
PAINT GREEN (-4265 9390);
DISPLAY INVISIBLE (-4265 9390);
FORCEADD VCC..1
(-4300 8850);
FORCEPROP 3 LASTPIN (-4250 8800) SIG_NAME XP3R3V_FPGA\g
J 0
(-4240 8810);
DISPLAY 0.659574 (-4240 8810);
PAINT MONO (-4240 8810);
DISPLAY INVISIBLE (-4240 8810);
FORCEPROP 0 LAST VOLTAGE 3.3V
J 0
(-4550 9000);
DISPLAY 1.021277 (-4550 9000);
DISPLAY BOTH (-4550 9000);
FORCEPROP 1 LAST HDL_POWER XP3R3V_FPGA
J 1
(-4245 8905);
DISPLAY 1.021277 (-4245 8905);
PAINT GREEN (-4245 8905);
FORCEPROP 1 LAST CDS_LMAN_SYM_OUTLINE -250,250,250,-250
J 0
(-4300 8850);
DISPLAY 0.468085 (-4300 8850);
PAINT GREEN (-4300 8850);
DISPLAY INVISIBLE (-4300 8850);
FORCEPROP 2 LAST CDS_LIB cls
J 0
(-4300 8850);
DISPLAY INVISIBLE (-4300 8850);
FORCEPROP 1 LAST BODY_TYPE PLUMBING
J 0
(-4345 8807);
DISPLAY 0.340426 (-4345 8807);
PAINT GREEN (-4345 8807);
DISPLAY INVISIBLE (-4345 8807);
FORCEPROP 1 LAST PATH I1224
J 0
(-4265 8940);
DISPLAY 0.808511 (-4265 8940);
PAINT GREEN (-4265 8940);
DISPLAY INVISIBLE (-4265 8940);
FORCEADD TP_PIONT..1
(-3300 8250);
FORCEPROP 1 LAST $LOCATION TP60
J 0
(-3200 8250);
DISPLAY 0.808511 (-3200 8250);
PAINT GREEN (-3200 8250);
FORCEPROP 0 LAST CDS_LOCATION TP60
J 0
(-3200 8300);
DISPLAY 1.021277 (-3200 8300);
DISPLAY INVISIBLE (-3200 8300);
FORCEPROP 0 LAST $SEC 1
J 0
(-3200 8300);
DISPLAY 0.680851 (-3200 8300);
PAINT MONO (-3200 8300);
DISPLAY INVISIBLE (-3200 8300);
FORCEPROP 0 LAST CDS_SEC 1
J 0
(-3200 8300);
DISPLAY 1.021277 (-3200 8300);
DISPLAY INVISIBLE (-3200 8300);
FORCEPROP 0 LASTPIN (-3400 8250) $PN 1
J 2
(-3410 8260);
DISPLAY 0.680851 (-3410 8260);
PAINT MONO (-3410 8260);
FORCEPROP 1 LAST PATH I1233
J 0
(-3220 8363);
DISPLAY 0.808511 (-3220 8363);
PAINT GREEN (-3220 8363);
DISPLAY INVISIBLE (-3220 8363);
FORCEPROP 2 LAST CDS_LIB cls
J 0
(-3300 8250);
DISPLAY INVISIBLE (-3300 8250);
FORCEPROP 1 LAST CDS_LMAN_SYM_OUTLINE -50,50,50,-50
J 0
(-3300 8250);
DISPLAY 0.468085 (-3300 8250);
PAINT GREEN (-3300 8250);
DISPLAY INVISIBLE (-3300 8250);
FORCEPROP 1 LAST BOM_IGNORE TRUE
J 0
(-3424 8350);
DISPLAY 0.000000 (-3424 8350);
PAINT GREEN (-3424 8350);
DISPLAY INVISIBLE (-3424 8350);
FORCEPROP 1 LAST JEDEC_TYPE TP010CT020B030_PTH
J 0
(-3424 8350);
DISPLAY 0.000000 (-3424 8350);
PAINT GREEN (-3424 8350);
DISPLAY INVISIBLE (-3424 8350);
FORCEADD VCC..1
(-4300 8400);
FORCEPROP 3 LASTPIN (-4250 8350) SIG_NAME XP5R0V\g
J 0
(-4240 8360);
DISPLAY 0.659574 (-4240 8360);
PAINT MONO (-4240 8360);
DISPLAY INVISIBLE (-4240 8360);
FORCEPROP 1 LAST HDL_POWER XP5R0V
J 1
(-4245 8455);
DISPLAY 1.021277 (-4245 8455);
PAINT GREEN (-4245 8455);
FORCEPROP 0 LAST VOLTAGE 5.0
J 0
(-4450 8550);
DISPLAY 1.021277 (-4450 8550);
DISPLAY BOTH (-4450 8550);
FORCEPROP 1 LAST PATH I1234
J 0
(-4265 8490);
DISPLAY 0.808511 (-4265 8490);
PAINT GREEN (-4265 8490);
DISPLAY INVISIBLE (-4265 8490);
FORCEPROP 1 LAST BODY_TYPE PLUMBING
J 0
(-4345 8357);
DISPLAY 0.340426 (-4345 8357);
PAINT GREEN (-4345 8357);
DISPLAY INVISIBLE (-4345 8357);
FORCEPROP 2 LAST CDS_LIB cls
J 0
(-4300 8400);
DISPLAY INVISIBLE (-4300 8400);
FORCEPROP 1 LAST CDS_LMAN_SYM_OUTLINE -250,250,250,-250
J 0
(-4300 8400);
DISPLAY 0.468085 (-4300 8400);
PAINT GREEN (-4300 8400);
DISPLAY INVISIBLE (-4300 8400);
FORCEADD OFFPAGE_BI..1
R 4
(-13300 6550);
FORCEPROP 2 LAST $XR0 13H5<> 
J 0
(-13519 6550);
DISPLAY 0.638298 (-13519 6550);
PAINT MONO (-13519 6550);
FORCEPROP 2 LAST CDS_LIB cls
J 0
(-13300 6550);
DISPLAY INVISIBLE (-13300 6550);
FORCEPROP 1 LAST CDS_LMAN_SYM_OUTLINE -50,50,50,-50
R 2
J 0
(-13300 6550);
DISPLAY 0.468085 (-13300 6550);
PAINT GREEN (-13300 6550);
DISPLAY INVISIBLE (-13300 6550);
FORCEPROP 1 LAST BODY_TYPE COMMENT
R 2
J 0
(-13310 6415);
DISPLAY 0.808511 (-13310 6415);
PAINT GREEN (-13310 6415);
DISPLAY INVISIBLE (-13310 6415);
FORCEPROP 1 LAST OFFPAGE TRUE
R 2
J 0
(-13310 6495);
DISPLAY 0.808511 (-13310 6495);
PAINT GREEN (-13310 6495);
DISPLAY INVISIBLE (-13310 6495);
FORCEPROP 2 LAST PATH I1459
J 0
(-13500 6600);
DISPLAY 1.021277 (-13500 6600);
DISPLAY INVISIBLE (-13500 6600);
FORCEADD OFFPAGE_BI..1
R 4
(-13300 6450);
FORCEPROP 2 LAST $XR0 13H5<> 
J 0
(-13519 6450);
DISPLAY 0.638298 (-13519 6450);
PAINT MONO (-13519 6450);
FORCEPROP 2 LAST CDS_LIB cls
J 0
(-13300 6450);
DISPLAY INVISIBLE (-13300 6450);
FORCEPROP 1 LAST CDS_LMAN_SYM_OUTLINE -50,50,50,-50
R 2
J 0
(-13300 6450);
DISPLAY 0.468085 (-13300 6450);
PAINT GREEN (-13300 6450);
DISPLAY INVISIBLE (-13300 6450);
FORCEPROP 1 LAST BODY_TYPE COMMENT
R 2
J 0
(-13310 6315);
DISPLAY 0.808511 (-13310 6315);
PAINT GREEN (-13310 6315);
DISPLAY INVISIBLE (-13310 6315);
FORCEPROP 1 LAST OFFPAGE TRUE
R 2
J 0
(-13310 6395);
DISPLAY 0.808511 (-13310 6395);
PAINT GREEN (-13310 6395);
DISPLAY INVISIBLE (-13310 6395);
FORCEPROP 2 LAST PATH I1460
J 0
(-13500 6500);
DISPLAY 1.021277 (-13500 6500);
DISPLAY INVISIBLE (-13500 6500);
FORCEADD OFFPAGE_BI..1
R 4
(-13300 6150);
FORCEPROP 2 LAST $XR0 13J5<> 
J 0
(-13519 6150);
DISPLAY 0.638298 (-13519 6150);
PAINT MONO (-13519 6150);
FORCEPROP 2 LAST PATH I1461
J 0
(-13500 6200);
DISPLAY 1.021277 (-13500 6200);
DISPLAY INVISIBLE (-13500 6200);
FORCEPROP 1 LAST OFFPAGE TRUE
R 2
J 0
(-13310 6095);
DISPLAY 0.808511 (-13310 6095);
PAINT GREEN (-13310 6095);
DISPLAY INVISIBLE (-13310 6095);
FORCEPROP 1 LAST CDS_LMAN_SYM_OUTLINE -50,50,50,-50
R 2
J 0
(-13300 6150);
DISPLAY 0.468085 (-13300 6150);
PAINT GREEN (-13300 6150);
DISPLAY INVISIBLE (-13300 6150);
FORCEPROP 2 LAST CDS_LIB cls
J 0
(-13300 6150);
DISPLAY INVISIBLE (-13300 6150);
FORCEPROP 1 LAST BODY_TYPE COMMENT
R 2
J 0
(-13310 6015);
DISPLAY 0.808511 (-13310 6015);
PAINT GREEN (-13310 6015);
DISPLAY INVISIBLE (-13310 6015);
FORCEADD OFFPAGE_BI..1
R 4
(-13300 6050);
FORCEPROP 2 LAST $XR0 13J5<> 
J 0
(-13519 6050);
DISPLAY 0.638298 (-13519 6050);
PAINT MONO (-13519 6050);
FORCEPROP 2 LAST PATH I1463
J 0
(-13500 6100);
DISPLAY 1.021277 (-13500 6100);
DISPLAY INVISIBLE (-13500 6100);
FORCEPROP 1 LAST OFFPAGE TRUE
R 2
J 0
(-13310 5995);
DISPLAY 0.808511 (-13310 5995);
PAINT GREEN (-13310 5995);
DISPLAY INVISIBLE (-13310 5995);
FORCEPROP 1 LAST CDS_LMAN_SYM_OUTLINE -50,50,50,-50
R 2
J 0
(-13300 6050);
DISPLAY 0.468085 (-13300 6050);
PAINT GREEN (-13300 6050);
DISPLAY INVISIBLE (-13300 6050);
FORCEPROP 2 LAST CDS_LIB cls
J 0
(-13300 6050);
DISPLAY INVISIBLE (-13300 6050);
FORCEPROP 1 LAST BODY_TYPE COMMENT
R 2
J 0
(-13310 5915);
DISPLAY 0.808511 (-13310 5915);
PAINT GREEN (-13310 5915);
DISPLAY INVISIBLE (-13310 5915);
FORCEADD OFFPAGE_BI..1
R 6
(-12300 8650);
FORCEPROP 2 LAST $XR0 12H11<> 
J 0
(-12240 8650);
DISPLAY 0.638298 (-12240 8650);
PAINT MONO (-12240 8650);
FORCEPROP 2 LAST CDS_LIB cls
J 0
(-12300 8650);
DISPLAY INVISIBLE (-12300 8650);
FORCEPROP 1 LAST CDS_LMAN_SYM_OUTLINE -50,50,50,-50
J 0
(-12300 8650);
DISPLAY 0.468085 (-12300 8650);
PAINT GREEN (-12300 8650);
DISPLAY INVISIBLE (-12300 8650);
FORCEPROP 2 LAST PATH I1469
J 0
(-12200 8700);
DISPLAY 1.021277 (-12200 8700);
DISPLAY INVISIBLE (-12200 8700);
FORCEPROP 1 LAST OFFPAGE TRUE
J 0
(-12290 8557);
DISPLAY 0.808511 (-12290 8557);
PAINT GREEN (-12290 8557);
DISPLAY INVISIBLE (-12290 8557);
FORCEPROP 1 LAST BODY_TYPE COMMENT
J 0
(-12290 8477);
DISPLAY 0.808511 (-12290 8477);
PAINT GREEN (-12290 8477);
DISPLAY INVISIBLE (-12290 8477);
FORCEADD OFFPAGE_BI..1
R 6
(-12300 9050);
FORCEPROP 2 LAST $XR0 12H11<> 
J 0
(-12240 9050);
DISPLAY 0.638298 (-12240 9050);
PAINT MONO (-12240 9050);
FORCEPROP 2 LAST CDS_LIB cls
J 0
(-12300 9050);
DISPLAY INVISIBLE (-12300 9050);
FORCEPROP 1 LAST CDS_LMAN_SYM_OUTLINE -50,50,50,-50
J 0
(-12300 9050);
DISPLAY 0.468085 (-12300 9050);
PAINT GREEN (-12300 9050);
DISPLAY INVISIBLE (-12300 9050);
FORCEPROP 2 LAST PATH I1477
J 0
(-12200 9100);
DISPLAY 1.021277 (-12200 9100);
DISPLAY INVISIBLE (-12200 9100);
FORCEPROP 1 LAST OFFPAGE TRUE
J 0
(-12290 8957);
DISPLAY 0.808511 (-12290 8957);
PAINT GREEN (-12290 8957);
DISPLAY INVISIBLE (-12290 8957);
FORCEPROP 1 LAST BODY_TYPE COMMENT
J 0
(-12290 8877);
DISPLAY 0.808511 (-12290 8877);
PAINT GREEN (-12290 8877);
DISPLAY INVISIBLE (-12290 8877);
FORCEADD OFFPAGE_BI..1
R 6
(-12300 8850);
FORCEPROP 2 LAST $XR0 12H11<> 
J 0
(-12240 8850);
DISPLAY 0.638298 (-12240 8850);
PAINT MONO (-12240 8850);
FORCEPROP 2 LAST CDS_LIB cls
J 0
(-12300 8850);
DISPLAY INVISIBLE (-12300 8850);
FORCEPROP 1 LAST CDS_LMAN_SYM_OUTLINE -50,50,50,-50
J 0
(-12300 8850);
DISPLAY 0.468085 (-12300 8850);
PAINT GREEN (-12300 8850);
DISPLAY INVISIBLE (-12300 8850);
FORCEPROP 2 LAST PATH I1479
J 0
(-12200 8900);
DISPLAY 1.021277 (-12200 8900);
DISPLAY INVISIBLE (-12200 8900);
FORCEPROP 1 LAST OFFPAGE TRUE
J 0
(-12290 8757);
DISPLAY 0.808511 (-12290 8757);
PAINT GREEN (-12290 8757);
DISPLAY INVISIBLE (-12290 8757);
FORCEPROP 1 LAST BODY_TYPE COMMENT
J 0
(-12290 8677);
DISPLAY 0.808511 (-12290 8677);
PAINT GREEN (-12290 8677);
DISPLAY INVISIBLE (-12290 8677);
FORCEADD OFFPAGE_BI..1
R 6
(-12300 8950);
FORCEPROP 2 LAST $XR0 12H11<> 
J 0
(-12240 8950);
DISPLAY 0.638298 (-12240 8950);
PAINT MONO (-12240 8950);
FORCEPROP 1 LAST CDS_LMAN_SYM_OUTLINE -50,50,50,-50
J 0
(-12300 8950);
DISPLAY 0.468085 (-12300 8950);
PAINT GREEN (-12300 8950);
DISPLAY INVISIBLE (-12300 8950);
FORCEPROP 2 LAST CDS_LIB cls
J 0
(-12300 8950);
DISPLAY INVISIBLE (-12300 8950);
FORCEPROP 2 LAST PATH I1480
J 0
(-12200 9000);
DISPLAY 1.021277 (-12200 9000);
DISPLAY INVISIBLE (-12200 9000);
FORCEPROP 1 LAST OFFPAGE TRUE
J 0
(-12290 8857);
DISPLAY 0.808511 (-12290 8857);
PAINT GREEN (-12290 8857);
DISPLAY INVISIBLE (-12290 8857);
FORCEPROP 1 LAST BODY_TYPE COMMENT
J 0
(-12290 8777);
DISPLAY 0.808511 (-12290 8777);
PAINT GREEN (-12290 8777);
DISPLAY INVISIBLE (-12290 8777);
FORCEADD OFFPAGE_BI..1
R 6
(-12300 8750);
FORCEPROP 2 LAST $XR0 12H11<> 
J 0
(-12240 8750);
DISPLAY 0.638298 (-12240 8750);
PAINT MONO (-12240 8750);
FORCEPROP 2 LAST CDS_LIB cls
J 0
(-12300 8750);
DISPLAY INVISIBLE (-12300 8750);
FORCEPROP 1 LAST CDS_LMAN_SYM_OUTLINE -50,50,50,-50
J 0
(-12300 8750);
DISPLAY 0.468085 (-12300 8750);
PAINT GREEN (-12300 8750);
DISPLAY INVISIBLE (-12300 8750);
FORCEPROP 2 LAST PATH I1481
J 0
(-12200 8800);
DISPLAY 1.021277 (-12200 8800);
DISPLAY INVISIBLE (-12200 8800);
FORCEPROP 1 LAST OFFPAGE TRUE
J 0
(-12290 8657);
DISPLAY 0.808511 (-12290 8657);
PAINT GREEN (-12290 8657);
DISPLAY INVISIBLE (-12290 8657);
FORCEPROP 1 LAST BODY_TYPE COMMENT
J 0
(-12290 8577);
DISPLAY 0.808511 (-12290 8577);
PAINT GREEN (-12290 8577);
DISPLAY INVISIBLE (-12290 8577);
FORCEADD OFFPAGE_BI..1
R 6
(-12300 8550);
FORCEPROP 2 LAST $XR0 12H11<> 
J 0
(-12240 8550);
DISPLAY 0.638298 (-12240 8550);
PAINT MONO (-12240 8550);
FORCEPROP 2 LAST CDS_LIB cls
J 0
(-12300 8550);
DISPLAY INVISIBLE (-12300 8550);
FORCEPROP 1 LAST CDS_LMAN_SYM_OUTLINE -50,50,50,-50
J 0
(-12300 8550);
DISPLAY 0.468085 (-12300 8550);
PAINT GREEN (-12300 8550);
DISPLAY INVISIBLE (-12300 8550);
FORCEPROP 2 LAST PATH I1482
J 0
(-12200 8600);
DISPLAY 1.021277 (-12200 8600);
DISPLAY INVISIBLE (-12200 8600);
FORCEPROP 1 LAST OFFPAGE TRUE
J 0
(-12290 8457);
DISPLAY 0.808511 (-12290 8457);
PAINT GREEN (-12290 8457);
DISPLAY INVISIBLE (-12290 8457);
FORCEPROP 1 LAST BODY_TYPE COMMENT
J 0
(-12290 8377);
DISPLAY 0.808511 (-12290 8377);
PAINT GREEN (-12290 8377);
DISPLAY INVISIBLE (-12290 8377);
FORCEADD TP_PIONT..1
(-12350 6550);
FORCEPROP 1 LAST $LOCATION TP193
J 0
(-12250 6550);
DISPLAY 0.808511 (-12250 6550);
PAINT GREEN (-12250 6550);
FORCEPROP 0 LAST CDS_LOCATION TP193
J 0
(-12250 6600);
DISPLAY 1.021277 (-12250 6600);
DISPLAY INVISIBLE (-12250 6600);
FORCEPROP 0 LAST $SEC 1
J 0
(-12250 6600);
DISPLAY 0.680851 (-12250 6600);
PAINT MONO (-12250 6600);
DISPLAY INVISIBLE (-12250 6600);
FORCEPROP 0 LAST CDS_SEC 1
J 0
(-12250 6600);
DISPLAY 1.021277 (-12250 6600);
DISPLAY INVISIBLE (-12250 6600);
FORCEPROP 0 LASTPIN (-12450 6550) $PN 1
J 2
(-12460 6560);
DISPLAY 0.680851 (-12460 6560);
PAINT MONO (-12460 6560);
FORCEPROP 1 LAST JEDEC_TYPE TP010CT020B030_PTH
J 0
(-12474 6650);
DISPLAY 0.000000 (-12474 6650);
PAINT GREEN (-12474 6650);
DISPLAY INVISIBLE (-12474 6650);
FORCEPROP 1 LAST BOM_IGNORE TRUE
J 0
(-12474 6650);
DISPLAY 0.000000 (-12474 6650);
PAINT GREEN (-12474 6650);
DISPLAY INVISIBLE (-12474 6650);
FORCEPROP 1 LAST CDS_LMAN_SYM_OUTLINE -50,50,50,-50
J 0
(-12350 6550);
DISPLAY 0.468085 (-12350 6550);
PAINT GREEN (-12350 6550);
DISPLAY INVISIBLE (-12350 6550);
FORCEPROP 2 LAST CDS_LIB cls
J 0
(-12350 6550);
DISPLAY INVISIBLE (-12350 6550);
FORCEPROP 1 LAST PATH I1487
J 0
(-12270 6663);
DISPLAY 0.808511 (-12270 6663);
PAINT GREEN (-12270 6663);
DISPLAY INVISIBLE (-12270 6663);
FORCEADD TP_PIONT..1
(-12350 6450);
FORCEPROP 1 LAST $LOCATION TP194
J 0
(-12250 6450);
DISPLAY 0.808511 (-12250 6450);
PAINT GREEN (-12250 6450);
FORCEPROP 0 LAST CDS_LOCATION TP194
J 0
(-12250 6500);
DISPLAY 1.021277 (-12250 6500);
DISPLAY INVISIBLE (-12250 6500);
FORCEPROP 0 LAST $SEC 1
J 0
(-12250 6500);
DISPLAY 0.680851 (-12250 6500);
PAINT MONO (-12250 6500);
DISPLAY INVISIBLE (-12250 6500);
FORCEPROP 0 LAST CDS_SEC 1
J 0
(-12250 6500);
DISPLAY 1.021277 (-12250 6500);
DISPLAY INVISIBLE (-12250 6500);
FORCEPROP 0 LASTPIN (-12450 6450) $PN 1
J 2
(-12460 6460);
DISPLAY 0.680851 (-12460 6460);
PAINT MONO (-12460 6460);
FORCEPROP 1 LAST JEDEC_TYPE TP010CT020B030_PTH
J 0
(-12474 6550);
DISPLAY 0.000000 (-12474 6550);
PAINT GREEN (-12474 6550);
DISPLAY INVISIBLE (-12474 6550);
FORCEPROP 1 LAST BOM_IGNORE TRUE
J 0
(-12474 6550);
DISPLAY 0.000000 (-12474 6550);
PAINT GREEN (-12474 6550);
DISPLAY INVISIBLE (-12474 6550);
FORCEPROP 1 LAST CDS_LMAN_SYM_OUTLINE -50,50,50,-50
J 0
(-12350 6450);
DISPLAY 0.468085 (-12350 6450);
PAINT GREEN (-12350 6450);
DISPLAY INVISIBLE (-12350 6450);
FORCEPROP 2 LAST CDS_LIB cls
J 0
(-12350 6450);
DISPLAY INVISIBLE (-12350 6450);
FORCEPROP 1 LAST PATH I1488
J 0
(-12270 6563);
DISPLAY 0.808511 (-12270 6563);
PAINT GREEN (-12270 6563);
DISPLAY INVISIBLE (-12270 6563);
FORCEADD TP_PIONT..1
(-12350 6150);
FORCEPROP 1 LAST $LOCATION TP195
J 0
(-12250 6150);
DISPLAY 0.808511 (-12250 6150);
PAINT GREEN (-12250 6150);
FORCEPROP 0 LAST CDS_LOCATION TP195
J 0
(-12250 6200);
DISPLAY 1.021277 (-12250 6200);
DISPLAY INVISIBLE (-12250 6200);
FORCEPROP 0 LAST $SEC 1
J 0
(-12250 6200);
DISPLAY 0.680851 (-12250 6200);
PAINT MONO (-12250 6200);
DISPLAY INVISIBLE (-12250 6200);
FORCEPROP 0 LAST CDS_SEC 1
J 0
(-12250 6200);
DISPLAY 1.021277 (-12250 6200);
DISPLAY INVISIBLE (-12250 6200);
FORCEPROP 0 LASTPIN (-12450 6150) $PN 1
J 2
(-12460 6160);
DISPLAY 0.680851 (-12460 6160);
PAINT MONO (-12460 6160);
FORCEPROP 1 LAST PATH I1489
J 0
(-12270 6263);
DISPLAY 0.808511 (-12270 6263);
PAINT GREEN (-12270 6263);
DISPLAY INVISIBLE (-12270 6263);
FORCEPROP 1 LAST JEDEC_TYPE TP010CT020B030_PTH
J 0
(-12474 6250);
DISPLAY 0.000000 (-12474 6250);
PAINT GREEN (-12474 6250);
DISPLAY INVISIBLE (-12474 6250);
FORCEPROP 1 LAST BOM_IGNORE TRUE
J 0
(-12474 6250);
DISPLAY 0.000000 (-12474 6250);
PAINT GREEN (-12474 6250);
DISPLAY INVISIBLE (-12474 6250);
FORCEPROP 1 LAST CDS_LMAN_SYM_OUTLINE -50,50,50,-50
J 0
(-12350 6150);
DISPLAY 0.468085 (-12350 6150);
PAINT GREEN (-12350 6150);
DISPLAY INVISIBLE (-12350 6150);
FORCEPROP 2 LAST CDS_LIB cls
J 0
(-12350 6150);
DISPLAY INVISIBLE (-12350 6150);
FORCEADD TP_PIONT..1
(-12350 6050);
FORCEPROP 1 LAST $LOCATION TP196
J 0
(-12250 6050);
DISPLAY 0.808511 (-12250 6050);
PAINT GREEN (-12250 6050);
FORCEPROP 0 LAST CDS_LOCATION TP196
J 0
(-12250 6100);
DISPLAY 1.021277 (-12250 6100);
DISPLAY INVISIBLE (-12250 6100);
FORCEPROP 0 LAST $SEC 1
J 0
(-12250 6100);
DISPLAY 0.680851 (-12250 6100);
PAINT MONO (-12250 6100);
DISPLAY INVISIBLE (-12250 6100);
FORCEPROP 0 LAST CDS_SEC 1
J 0
(-12250 6100);
DISPLAY 1.021277 (-12250 6100);
DISPLAY INVISIBLE (-12250 6100);
FORCEPROP 0 LASTPIN (-12450 6050) $PN 1
J 2
(-12460 6060);
DISPLAY 0.680851 (-12460 6060);
PAINT MONO (-12460 6060);
FORCEPROP 1 LAST PATH I1490
J 0
(-12270 6163);
DISPLAY 0.808511 (-12270 6163);
PAINT GREEN (-12270 6163);
DISPLAY INVISIBLE (-12270 6163);
FORCEPROP 1 LAST JEDEC_TYPE TP010CT020B030_PTH
J 0
(-12474 6150);
DISPLAY 0.000000 (-12474 6150);
PAINT GREEN (-12474 6150);
DISPLAY INVISIBLE (-12474 6150);
FORCEPROP 1 LAST BOM_IGNORE TRUE
J 0
(-12474 6150);
DISPLAY 0.000000 (-12474 6150);
PAINT GREEN (-12474 6150);
DISPLAY INVISIBLE (-12474 6150);
FORCEPROP 1 LAST CDS_LMAN_SYM_OUTLINE -50,50,50,-50
J 0
(-12350 6050);
DISPLAY 0.468085 (-12350 6050);
PAINT GREEN (-12350 6050);
DISPLAY INVISIBLE (-12350 6050);
FORCEPROP 2 LAST CDS_LIB cls
J 0
(-12350 6050);
DISPLAY INVISIBLE (-12350 6050);
FORCEADD TP_PIONT..1
R 2
(-13300 9050);
FORCEPROP 1 LAST $LOCATION TP183
J 2
(-13350 9050);
DISPLAY 0.808511 (-13350 9050);
PAINT GREEN (-13350 9050);
FORCEPROP 0 LAST CDS_LOCATION TP183
J 0
(-13350 9100);
DISPLAY 1.021277 (-13350 9100);
DISPLAY INVISIBLE (-13350 9100);
FORCEPROP 0 LAST $SEC 1
J 0
(-13350 9100);
DISPLAY 0.680851 (-13350 9100);
PAINT MONO (-13350 9100);
DISPLAY INVISIBLE (-13350 9100);
FORCEPROP 0 LAST CDS_SEC 1
J 0
(-13350 9100);
DISPLAY 1.021277 (-13350 9100);
DISPLAY INVISIBLE (-13350 9100);
FORCEPROP 0 LASTPIN (-13200 9050) $PN 1
J 0
(-13190 9060);
DISPLAY 0.680851 (-13190 9060);
PAINT MONO (-13190 9060);
FORCEPROP 2 LAST CDS_LIB cls
J 2
(-13300 9050);
DISPLAY INVISIBLE (-13300 9050);
FORCEPROP 1 LAST CDS_LMAN_SYM_OUTLINE -50,50,50,-50
J 2
(-13300 9050);
DISPLAY 0.468085 (-13300 9050);
PAINT GREEN (-13300 9050);
DISPLAY INVISIBLE (-13300 9050);
FORCEPROP 1 LAST PATH I1505
J 2
(-13380 9163);
DISPLAY 0.808511 (-13380 9163);
PAINT GREEN (-13380 9163);
DISPLAY INVISIBLE (-13380 9163);
FORCEPROP 1 LAST BOM_IGNORE TRUE
J 2
(-13176 9150);
DISPLAY 0.000000 (-13176 9150);
PAINT GREEN (-13176 9150);
DISPLAY INVISIBLE (-13176 9150);
FORCEPROP 1 LAST JEDEC_TYPE TP010CT020B030_PTH
J 2
(-13176 9150);
DISPLAY 0.000000 (-13176 9150);
PAINT GREEN (-13176 9150);
DISPLAY INVISIBLE (-13176 9150);
FORCEADD TP_PIONT..1
R 2
(-13300 8950);
FORCEPROP 1 LAST $LOCATION TP184
J 2
(-13350 8950);
DISPLAY 0.808511 (-13350 8950);
PAINT GREEN (-13350 8950);
FORCEPROP 0 LAST CDS_LOCATION TP184
J 0
(-13350 9000);
DISPLAY 1.021277 (-13350 9000);
DISPLAY INVISIBLE (-13350 9000);
FORCEPROP 0 LAST $SEC 1
J 0
(-13350 9000);
DISPLAY 0.680851 (-13350 9000);
PAINT MONO (-13350 9000);
DISPLAY INVISIBLE (-13350 9000);
FORCEPROP 0 LAST CDS_SEC 1
J 0
(-13350 9000);
DISPLAY 1.021277 (-13350 9000);
DISPLAY INVISIBLE (-13350 9000);
FORCEPROP 0 LASTPIN (-13200 8950) $PN 1
J 0
(-13190 8960);
DISPLAY 0.680851 (-13190 8960);
PAINT MONO (-13190 8960);
FORCEPROP 2 LAST CDS_LIB cls
J 2
(-13300 8950);
DISPLAY INVISIBLE (-13300 8950);
FORCEPROP 1 LAST CDS_LMAN_SYM_OUTLINE -50,50,50,-50
J 2
(-13300 8950);
DISPLAY 0.468085 (-13300 8950);
PAINT GREEN (-13300 8950);
DISPLAY INVISIBLE (-13300 8950);
FORCEPROP 1 LAST PATH I1506
J 2
(-13380 9063);
DISPLAY 0.808511 (-13380 9063);
PAINT GREEN (-13380 9063);
DISPLAY INVISIBLE (-13380 9063);
FORCEPROP 1 LAST BOM_IGNORE TRUE
J 2
(-13176 9050);
DISPLAY 0.000000 (-13176 9050);
PAINT GREEN (-13176 9050);
DISPLAY INVISIBLE (-13176 9050);
FORCEPROP 1 LAST JEDEC_TYPE TP010CT020B030_PTH
J 2
(-13176 9050);
DISPLAY 0.000000 (-13176 9050);
PAINT GREEN (-13176 9050);
DISPLAY INVISIBLE (-13176 9050);
FORCEADD TP_PIONT..1
R 2
(-13300 8850);
FORCEPROP 1 LAST $LOCATION TP185
J 2
(-13350 8850);
DISPLAY 0.808511 (-13350 8850);
PAINT GREEN (-13350 8850);
FORCEPROP 0 LAST CDS_LOCATION TP185
J 0
(-13350 8900);
DISPLAY 1.021277 (-13350 8900);
DISPLAY INVISIBLE (-13350 8900);
FORCEPROP 0 LAST $SEC 1
J 0
(-13350 8900);
DISPLAY 0.680851 (-13350 8900);
PAINT MONO (-13350 8900);
DISPLAY INVISIBLE (-13350 8900);
FORCEPROP 0 LAST CDS_SEC 1
J 0
(-13350 8900);
DISPLAY 1.021277 (-13350 8900);
DISPLAY INVISIBLE (-13350 8900);
FORCEPROP 0 LASTPIN (-13200 8850) $PN 1
J 0
(-13190 8860);
DISPLAY 0.680851 (-13190 8860);
PAINT MONO (-13190 8860);
FORCEPROP 2 LAST CDS_LIB cls
J 2
(-13300 8850);
DISPLAY INVISIBLE (-13300 8850);
FORCEPROP 1 LAST CDS_LMAN_SYM_OUTLINE -50,50,50,-50
J 2
(-13300 8850);
DISPLAY 0.468085 (-13300 8850);
PAINT GREEN (-13300 8850);
DISPLAY INVISIBLE (-13300 8850);
FORCEPROP 1 LAST PATH I1507
J 2
(-13380 8963);
DISPLAY 0.808511 (-13380 8963);
PAINT GREEN (-13380 8963);
DISPLAY INVISIBLE (-13380 8963);
FORCEPROP 1 LAST BOM_IGNORE TRUE
J 2
(-13176 8950);
DISPLAY 0.000000 (-13176 8950);
PAINT GREEN (-13176 8950);
DISPLAY INVISIBLE (-13176 8950);
FORCEPROP 1 LAST JEDEC_TYPE TP010CT020B030_PTH
J 2
(-13176 8950);
DISPLAY 0.000000 (-13176 8950);
PAINT GREEN (-13176 8950);
DISPLAY INVISIBLE (-13176 8950);
FORCEADD TP_PIONT..1
R 2
(-13300 8750);
FORCEPROP 1 LAST $LOCATION TP186
J 2
(-13350 8750);
DISPLAY 0.808511 (-13350 8750);
PAINT GREEN (-13350 8750);
FORCEPROP 0 LAST CDS_LOCATION TP186
J 0
(-13350 8800);
DISPLAY 1.021277 (-13350 8800);
DISPLAY INVISIBLE (-13350 8800);
FORCEPROP 0 LAST $SEC 1
J 0
(-13350 8800);
DISPLAY 0.680851 (-13350 8800);
PAINT MONO (-13350 8800);
DISPLAY INVISIBLE (-13350 8800);
FORCEPROP 0 LAST CDS_SEC 1
J 0
(-13350 8800);
DISPLAY 1.021277 (-13350 8800);
DISPLAY INVISIBLE (-13350 8800);
FORCEPROP 0 LASTPIN (-13200 8750) $PN 1
J 0
(-13190 8760);
DISPLAY 0.680851 (-13190 8760);
PAINT MONO (-13190 8760);
FORCEPROP 2 LAST CDS_LIB cls
J 2
(-13300 8750);
DISPLAY INVISIBLE (-13300 8750);
FORCEPROP 1 LAST CDS_LMAN_SYM_OUTLINE -50,50,50,-50
J 2
(-13300 8750);
DISPLAY 0.468085 (-13300 8750);
PAINT GREEN (-13300 8750);
DISPLAY INVISIBLE (-13300 8750);
FORCEPROP 1 LAST PATH I1508
J 2
(-13380 8863);
DISPLAY 0.808511 (-13380 8863);
PAINT GREEN (-13380 8863);
DISPLAY INVISIBLE (-13380 8863);
FORCEPROP 1 LAST BOM_IGNORE TRUE
J 2
(-13176 8850);
DISPLAY 0.000000 (-13176 8850);
PAINT GREEN (-13176 8850);
DISPLAY INVISIBLE (-13176 8850);
FORCEPROP 1 LAST JEDEC_TYPE TP010CT020B030_PTH
J 2
(-13176 8850);
DISPLAY 0.000000 (-13176 8850);
PAINT GREEN (-13176 8850);
DISPLAY INVISIBLE (-13176 8850);
FORCEADD TP_PIONT..1
R 2
(-13300 8650);
FORCEPROP 1 LAST $LOCATION TP187
J 2
(-13350 8650);
DISPLAY 0.808511 (-13350 8650);
PAINT GREEN (-13350 8650);
FORCEPROP 0 LAST CDS_LOCATION TP187
J 0
(-13350 8700);
DISPLAY 1.021277 (-13350 8700);
DISPLAY INVISIBLE (-13350 8700);
FORCEPROP 0 LAST $SEC 1
J 0
(-13350 8700);
DISPLAY 0.680851 (-13350 8700);
PAINT MONO (-13350 8700);
DISPLAY INVISIBLE (-13350 8700);
FORCEPROP 0 LAST CDS_SEC 1
J 0
(-13350 8700);
DISPLAY 1.021277 (-13350 8700);
DISPLAY INVISIBLE (-13350 8700);
FORCEPROP 0 LASTPIN (-13200 8650) $PN 1
J 0
(-13190 8660);
DISPLAY 0.680851 (-13190 8660);
PAINT MONO (-13190 8660);
FORCEPROP 2 LAST CDS_LIB cls
J 2
(-13300 8650);
DISPLAY INVISIBLE (-13300 8650);
FORCEPROP 1 LAST CDS_LMAN_SYM_OUTLINE -50,50,50,-50
J 2
(-13300 8650);
DISPLAY 0.468085 (-13300 8650);
PAINT GREEN (-13300 8650);
DISPLAY INVISIBLE (-13300 8650);
FORCEPROP 1 LAST PATH I1509
J 2
(-13380 8763);
DISPLAY 0.808511 (-13380 8763);
PAINT GREEN (-13380 8763);
DISPLAY INVISIBLE (-13380 8763);
FORCEPROP 1 LAST BOM_IGNORE TRUE
J 2
(-13176 8750);
DISPLAY 0.000000 (-13176 8750);
PAINT GREEN (-13176 8750);
DISPLAY INVISIBLE (-13176 8750);
FORCEPROP 1 LAST JEDEC_TYPE TP010CT020B030_PTH
J 2
(-13176 8750);
DISPLAY 0.000000 (-13176 8750);
PAINT GREEN (-13176 8750);
DISPLAY INVISIBLE (-13176 8750);
FORCEADD TP_PIONT..1
R 2
(-13300 8550);
FORCEPROP 1 LAST $LOCATION TP188
J 2
(-13350 8550);
DISPLAY 0.808511 (-13350 8550);
PAINT GREEN (-13350 8550);
FORCEPROP 0 LAST CDS_LOCATION TP188
J 0
(-13350 8600);
DISPLAY 1.021277 (-13350 8600);
DISPLAY INVISIBLE (-13350 8600);
FORCEPROP 0 LAST $SEC 1
J 0
(-13350 8600);
DISPLAY 0.680851 (-13350 8600);
PAINT MONO (-13350 8600);
DISPLAY INVISIBLE (-13350 8600);
FORCEPROP 0 LAST CDS_SEC 1
J 0
(-13350 8600);
DISPLAY 1.021277 (-13350 8600);
DISPLAY INVISIBLE (-13350 8600);
FORCEPROP 0 LASTPIN (-13200 8550) $PN 1
J 0
(-13190 8560);
DISPLAY 0.680851 (-13190 8560);
PAINT MONO (-13190 8560);
FORCEPROP 2 LAST CDS_LIB cls
J 2
(-13300 8550);
DISPLAY INVISIBLE (-13300 8550);
FORCEPROP 1 LAST CDS_LMAN_SYM_OUTLINE -50,50,50,-50
J 2
(-13300 8550);
DISPLAY 0.468085 (-13300 8550);
PAINT GREEN (-13300 8550);
DISPLAY INVISIBLE (-13300 8550);
FORCEPROP 1 LAST PATH I1510
J 2
(-13380 8663);
DISPLAY 0.808511 (-13380 8663);
PAINT GREEN (-13380 8663);
DISPLAY INVISIBLE (-13380 8663);
FORCEPROP 1 LAST BOM_IGNORE TRUE
J 2
(-13176 8650);
DISPLAY 0.000000 (-13176 8650);
PAINT GREEN (-13176 8650);
DISPLAY INVISIBLE (-13176 8650);
FORCEPROP 1 LAST JEDEC_TYPE TP010CT020B030_PTH
J 2
(-13176 8650);
DISPLAY 0.000000 (-13176 8650);
PAINT GREEN (-13176 8650);
DISPLAY INVISIBLE (-13176 8650);
FORCEADD TP_PIONT..1
R 2
(-13300 9400);
FORCEPROP 1 LAST $LOCATION TP180
J 2
(-13350 9400);
DISPLAY 0.808511 (-13350 9400);
PAINT GREEN (-13350 9400);
FORCEPROP 0 LAST CDS_LOCATION TP180
J 0
(-13350 9450);
DISPLAY 1.021277 (-13350 9450);
DISPLAY INVISIBLE (-13350 9450);
FORCEPROP 0 LAST $SEC 1
J 0
(-13350 9450);
DISPLAY 0.680851 (-13350 9450);
PAINT MONO (-13350 9450);
DISPLAY INVISIBLE (-13350 9450);
FORCEPROP 0 LAST CDS_SEC 1
J 0
(-13350 9450);
DISPLAY 1.021277 (-13350 9450);
DISPLAY INVISIBLE (-13350 9450);
FORCEPROP 0 LASTPIN (-13200 9400) $PN 1
J 0
(-13190 9410);
DISPLAY 0.680851 (-13190 9410);
PAINT MONO (-13190 9410);
FORCEPROP 2 LAST CDS_LIB cls
J 2
(-13300 9400);
DISPLAY INVISIBLE (-13300 9400);
FORCEPROP 1 LAST CDS_LMAN_SYM_OUTLINE -50,50,50,-50
J 2
(-13300 9400);
DISPLAY 0.468085 (-13300 9400);
PAINT GREEN (-13300 9400);
DISPLAY INVISIBLE (-13300 9400);
FORCEPROP 1 LAST PATH I1511
J 2
(-13380 9513);
DISPLAY 0.808511 (-13380 9513);
PAINT GREEN (-13380 9513);
DISPLAY INVISIBLE (-13380 9513);
FORCEPROP 1 LAST BOM_IGNORE TRUE
J 2
(-13176 9500);
DISPLAY 0.000000 (-13176 9500);
PAINT GREEN (-13176 9500);
DISPLAY INVISIBLE (-13176 9500);
FORCEPROP 1 LAST JEDEC_TYPE TP010CT020B030_PTH
J 2
(-13176 9500);
DISPLAY 0.000000 (-13176 9500);
PAINT GREEN (-13176 9500);
DISPLAY INVISIBLE (-13176 9500);
FORCEADD TP_PIONT..1
R 2
(-13300 9300);
FORCEPROP 1 LAST $LOCATION TP181
J 2
(-13350 9300);
DISPLAY 0.808511 (-13350 9300);
PAINT GREEN (-13350 9300);
FORCEPROP 0 LAST CDS_LOCATION TP181
J 0
(-13350 9350);
DISPLAY 1.021277 (-13350 9350);
DISPLAY INVISIBLE (-13350 9350);
FORCEPROP 0 LAST $SEC 1
J 0
(-13350 9350);
DISPLAY 0.680851 (-13350 9350);
PAINT MONO (-13350 9350);
DISPLAY INVISIBLE (-13350 9350);
FORCEPROP 0 LAST CDS_SEC 1
J 0
(-13350 9350);
DISPLAY 1.021277 (-13350 9350);
DISPLAY INVISIBLE (-13350 9350);
FORCEPROP 0 LASTPIN (-13200 9300) $PN 1
J 0
(-13190 9310);
DISPLAY 0.680851 (-13190 9310);
PAINT MONO (-13190 9310);
FORCEPROP 2 LAST CDS_LIB cls
J 2
(-13300 9300);
DISPLAY INVISIBLE (-13300 9300);
FORCEPROP 1 LAST CDS_LMAN_SYM_OUTLINE -50,50,50,-50
J 2
(-13300 9300);
DISPLAY 0.468085 (-13300 9300);
PAINT GREEN (-13300 9300);
DISPLAY INVISIBLE (-13300 9300);
FORCEPROP 1 LAST PATH I1512
J 2
(-13380 9413);
DISPLAY 0.808511 (-13380 9413);
PAINT GREEN (-13380 9413);
DISPLAY INVISIBLE (-13380 9413);
FORCEPROP 1 LAST BOM_IGNORE TRUE
J 2
(-13176 9400);
DISPLAY 0.000000 (-13176 9400);
PAINT GREEN (-13176 9400);
DISPLAY INVISIBLE (-13176 9400);
FORCEPROP 1 LAST JEDEC_TYPE TP010CT020B030_PTH
J 2
(-13176 9400);
DISPLAY 0.000000 (-13176 9400);
PAINT GREEN (-13176 9400);
DISPLAY INVISIBLE (-13176 9400);
FORCEADD TP_PIONT..1
R 2
(-13300 9200);
FORCEPROP 1 LAST $LOCATION TP182
J 2
(-13350 9200);
DISPLAY 0.808511 (-13350 9200);
PAINT GREEN (-13350 9200);
FORCEPROP 0 LAST CDS_LOCATION TP182
J 0
(-13350 9250);
DISPLAY 1.021277 (-13350 9250);
DISPLAY INVISIBLE (-13350 9250);
FORCEPROP 0 LAST $SEC 1
J 0
(-13350 9250);
DISPLAY 0.680851 (-13350 9250);
PAINT MONO (-13350 9250);
DISPLAY INVISIBLE (-13350 9250);
FORCEPROP 0 LAST CDS_SEC 1
J 0
(-13350 9250);
DISPLAY 1.021277 (-13350 9250);
DISPLAY INVISIBLE (-13350 9250);
FORCEPROP 0 LASTPIN (-13200 9200) $PN 1
J 0
(-13190 9210);
DISPLAY 0.680851 (-13190 9210);
PAINT MONO (-13190 9210);
FORCEPROP 2 LAST CDS_LIB cls
J 2
(-13300 9200);
DISPLAY INVISIBLE (-13300 9200);
FORCEPROP 1 LAST CDS_LMAN_SYM_OUTLINE -50,50,50,-50
J 2
(-13300 9200);
DISPLAY 0.468085 (-13300 9200);
PAINT GREEN (-13300 9200);
DISPLAY INVISIBLE (-13300 9200);
FORCEPROP 1 LAST PATH I1513
J 2
(-13380 9313);
DISPLAY 0.808511 (-13380 9313);
PAINT GREEN (-13380 9313);
DISPLAY INVISIBLE (-13380 9313);
FORCEPROP 1 LAST BOM_IGNORE TRUE
J 2
(-13176 9300);
DISPLAY 0.000000 (-13176 9300);
PAINT GREEN (-13176 9300);
DISPLAY INVISIBLE (-13176 9300);
FORCEPROP 1 LAST JEDEC_TYPE TP010CT020B030_PTH
J 2
(-13176 9300);
DISPLAY 0.000000 (-13176 9300);
PAINT GREEN (-13176 9300);
DISPLAY INVISIBLE (-13176 9300);
FORCEADD TP_PIONT..1
R 2
(-13300 9500);
FORCEPROP 1 LAST $LOCATION TP78
J 2
(-13350 9500);
DISPLAY 0.808511 (-13350 9500);
PAINT GREEN (-13350 9500);
FORCEPROP 0 LAST CDS_LOCATION TP78
J 0
(-13350 9550);
DISPLAY 1.021277 (-13350 9550);
DISPLAY INVISIBLE (-13350 9550);
FORCEPROP 0 LAST $SEC 1
J 0
(-13350 9550);
DISPLAY 0.680851 (-13350 9550);
PAINT MONO (-13350 9550);
DISPLAY INVISIBLE (-13350 9550);
FORCEPROP 0 LAST CDS_SEC 1
J 0
(-13350 9550);
DISPLAY 1.021277 (-13350 9550);
DISPLAY INVISIBLE (-13350 9550);
FORCEPROP 0 LASTPIN (-13200 9500) $PN 1
J 0
(-13190 9510);
DISPLAY 0.680851 (-13190 9510);
PAINT MONO (-13190 9510);
FORCEPROP 2 LAST CDS_LIB cls
J 2
(-13300 9500);
DISPLAY INVISIBLE (-13300 9500);
FORCEPROP 1 LAST CDS_LMAN_SYM_OUTLINE -50,50,50,-50
J 2
(-13300 9500);
DISPLAY 0.468085 (-13300 9500);
PAINT GREEN (-13300 9500);
DISPLAY INVISIBLE (-13300 9500);
FORCEPROP 1 LAST PATH I1516
J 2
(-13380 9613);
DISPLAY 0.808511 (-13380 9613);
PAINT GREEN (-13380 9613);
DISPLAY INVISIBLE (-13380 9613);
FORCEPROP 1 LAST BOM_IGNORE TRUE
J 2
(-13176 9600);
DISPLAY 0.000000 (-13176 9600);
PAINT GREEN (-13176 9600);
DISPLAY INVISIBLE (-13176 9600);
FORCEPROP 1 LAST JEDEC_TYPE TP010CT020B030_PTH
J 2
(-13176 9600);
DISPLAY 0.000000 (-13176 9600);
PAINT GREEN (-13176 9600);
DISPLAY INVISIBLE (-13176 9600);
FORCEADD OFFPAGE_BI..1
R 6
(-12300 9500);
FORCEPROP 2 LAST $XR0 12G11<> 
J 0
(-12240 9500);
DISPLAY 0.638298 (-12240 9500);
PAINT MONO (-12240 9500);
FORCEPROP 1 LAST CDS_LMAN_SYM_OUTLINE -50,50,50,-50
J 0
(-12300 9500);
DISPLAY 0.468085 (-12300 9500);
PAINT GREEN (-12300 9500);
DISPLAY INVISIBLE (-12300 9500);
FORCEPROP 2 LAST CDS_LIB cls
J 0
(-12300 9500);
DISPLAY INVISIBLE (-12300 9500);
FORCEPROP 2 LAST PATH I1519
J 0
(-12250 9600);
DISPLAY 1.021277 (-12250 9600);
DISPLAY INVISIBLE (-12250 9600);
FORCEPROP 1 LAST OFFPAGE TRUE
J 0
(-12290 9407);
DISPLAY 0.808511 (-12290 9407);
PAINT GREEN (-12290 9407);
DISPLAY INVISIBLE (-12290 9407);
FORCEPROP 1 LAST BODY_TYPE COMMENT
J 0
(-12290 9327);
DISPLAY 0.808511 (-12290 9327);
PAINT GREEN (-12290 9327);
DISPLAY INVISIBLE (-12290 9327);
FORCEADD OFFPAGE_BI..1
R 6
(-12300 9400);
FORCEPROP 2 LAST $XR0 12H11<> 
J 0
(-12240 9400);
DISPLAY 0.638298 (-12240 9400);
PAINT MONO (-12240 9400);
FORCEPROP 1 LAST CDS_LMAN_SYM_OUTLINE -50,50,50,-50
J 0
(-12300 9400);
DISPLAY 0.468085 (-12300 9400);
PAINT GREEN (-12300 9400);
DISPLAY INVISIBLE (-12300 9400);
FORCEPROP 2 LAST CDS_LIB cls
J 0
(-12300 9400);
DISPLAY INVISIBLE (-12300 9400);
FORCEPROP 2 LAST PATH I1520
J 0
(-12250 9500);
DISPLAY 1.021277 (-12250 9500);
DISPLAY INVISIBLE (-12250 9500);
FORCEPROP 1 LAST OFFPAGE TRUE
J 0
(-12290 9307);
DISPLAY 0.808511 (-12290 9307);
PAINT GREEN (-12290 9307);
DISPLAY INVISIBLE (-12290 9307);
FORCEPROP 1 LAST BODY_TYPE COMMENT
J 0
(-12290 9227);
DISPLAY 0.808511 (-12290 9227);
PAINT GREEN (-12290 9227);
DISPLAY INVISIBLE (-12290 9227);
FORCEADD OFFPAGE_BI..1
R 6
(-12300 9300);
FORCEPROP 2 LAST $XR0 12H11<> 
J 0
(-12240 9300);
DISPLAY 0.638298 (-12240 9300);
PAINT MONO (-12240 9300);
FORCEPROP 1 LAST CDS_LMAN_SYM_OUTLINE -50,50,50,-50
J 0
(-12300 9300);
DISPLAY 0.468085 (-12300 9300);
PAINT GREEN (-12300 9300);
DISPLAY INVISIBLE (-12300 9300);
FORCEPROP 2 LAST CDS_LIB cls
J 0
(-12300 9300);
DISPLAY INVISIBLE (-12300 9300);
FORCEPROP 2 LAST PATH I1521
J 0
(-12250 9400);
DISPLAY 1.021277 (-12250 9400);
DISPLAY INVISIBLE (-12250 9400);
FORCEPROP 1 LAST OFFPAGE TRUE
J 0
(-12290 9207);
DISPLAY 0.808511 (-12290 9207);
PAINT GREEN (-12290 9207);
DISPLAY INVISIBLE (-12290 9207);
FORCEPROP 1 LAST BODY_TYPE COMMENT
J 0
(-12290 9127);
DISPLAY 0.808511 (-12290 9127);
PAINT GREEN (-12290 9127);
DISPLAY INVISIBLE (-12290 9127);
FORCEADD OFFPAGE_BI..1
R 6
(-12300 9200);
FORCEPROP 2 LAST $XR0 12H11<> 
J 0
(-12240 9200);
DISPLAY 0.638298 (-12240 9200);
PAINT MONO (-12240 9200);
FORCEPROP 1 LAST CDS_LMAN_SYM_OUTLINE -50,50,50,-50
J 0
(-12300 9200);
DISPLAY 0.468085 (-12300 9200);
PAINT GREEN (-12300 9200);
DISPLAY INVISIBLE (-12300 9200);
FORCEPROP 2 LAST CDS_LIB cls
J 0
(-12300 9200);
DISPLAY INVISIBLE (-12300 9200);
FORCEPROP 2 LAST PATH I1522
J 0
(-12250 9300);
DISPLAY 1.021277 (-12250 9300);
DISPLAY INVISIBLE (-12250 9300);
FORCEPROP 1 LAST OFFPAGE TRUE
J 0
(-12290 9107);
DISPLAY 0.808511 (-12290 9107);
PAINT GREEN (-12290 9107);
DISPLAY INVISIBLE (-12290 9107);
FORCEPROP 1 LAST BODY_TYPE COMMENT
J 0
(-12290 9027);
DISPLAY 0.808511 (-12290 9027);
PAINT GREEN (-12290 9027);
DISPLAY INVISIBLE (-12290 9027);
FORCEADD TP_PIONT..1
(-12350 5950);
FORCEPROP 1 LAST $LOCATION TP203
J 0
(-12250 5950);
DISPLAY 0.808511 (-12250 5950);
PAINT GREEN (-12250 5950);
FORCEPROP 0 LAST CDS_LOCATION TP203
J 0
(-12250 6000);
DISPLAY 1.021277 (-12250 6000);
DISPLAY INVISIBLE (-12250 6000);
FORCEPROP 0 LAST $SEC 1
J 0
(-12250 6000);
DISPLAY 0.680851 (-12250 6000);
PAINT MONO (-12250 6000);
DISPLAY INVISIBLE (-12250 6000);
FORCEPROP 0 LAST CDS_SEC 1
J 0
(-12250 6000);
DISPLAY 1.021277 (-12250 6000);
DISPLAY INVISIBLE (-12250 6000);
FORCEPROP 0 LASTPIN (-12450 5950) $PN 1
J 2
(-12460 5960);
DISPLAY 0.680851 (-12460 5960);
PAINT MONO (-12460 5960);
FORCEPROP 2 LAST CDS_LIB cls
J 0
(-12350 5950);
DISPLAY INVISIBLE (-12350 5950);
FORCEPROP 1 LAST CDS_LMAN_SYM_OUTLINE -50,50,50,-50
J 0
(-12350 5950);
DISPLAY 0.468085 (-12350 5950);
PAINT GREEN (-12350 5950);
DISPLAY INVISIBLE (-12350 5950);
FORCEPROP 1 LAST BOM_IGNORE TRUE
J 0
(-12474 6050);
DISPLAY 0.000000 (-12474 6050);
PAINT GREEN (-12474 6050);
DISPLAY INVISIBLE (-12474 6050);
FORCEPROP 1 LAST JEDEC_TYPE TP010CT020B030_PTH
J 0
(-12474 6050);
DISPLAY 0.000000 (-12474 6050);
PAINT GREEN (-12474 6050);
DISPLAY INVISIBLE (-12474 6050);
FORCEPROP 1 LAST PATH I1523
J 0
(-12270 6063);
DISPLAY 0.808511 (-12270 6063);
PAINT GREEN (-12270 6063);
DISPLAY INVISIBLE (-12270 6063);
FORCEADD TP_PIONT..1
(-12350 5850);
FORCEPROP 1 LAST $LOCATION TP204
J 0
(-12250 5850);
DISPLAY 0.808511 (-12250 5850);
PAINT GREEN (-12250 5850);
FORCEPROP 0 LAST CDS_LOCATION TP204
J 0
(-12250 5900);
DISPLAY 1.021277 (-12250 5900);
DISPLAY INVISIBLE (-12250 5900);
FORCEPROP 0 LAST $SEC 1
J 0
(-12250 5900);
DISPLAY 0.680851 (-12250 5900);
PAINT MONO (-12250 5900);
DISPLAY INVISIBLE (-12250 5900);
FORCEPROP 0 LAST CDS_SEC 1
J 0
(-12250 5900);
DISPLAY 1.021277 (-12250 5900);
DISPLAY INVISIBLE (-12250 5900);
FORCEPROP 0 LASTPIN (-12450 5850) $PN 1
J 2
(-12460 5860);
DISPLAY 0.680851 (-12460 5860);
PAINT MONO (-12460 5860);
FORCEPROP 2 LAST CDS_LIB cls
J 0
(-12350 5850);
DISPLAY INVISIBLE (-12350 5850);
FORCEPROP 1 LAST CDS_LMAN_SYM_OUTLINE -50,50,50,-50
J 0
(-12350 5850);
DISPLAY 0.468085 (-12350 5850);
PAINT GREEN (-12350 5850);
DISPLAY INVISIBLE (-12350 5850);
FORCEPROP 1 LAST BOM_IGNORE TRUE
J 0
(-12474 5950);
DISPLAY 0.000000 (-12474 5950);
PAINT GREEN (-12474 5950);
DISPLAY INVISIBLE (-12474 5950);
FORCEPROP 1 LAST JEDEC_TYPE TP010CT020B030_PTH
J 0
(-12474 5950);
DISPLAY 0.000000 (-12474 5950);
PAINT GREEN (-12474 5950);
DISPLAY INVISIBLE (-12474 5950);
FORCEPROP 1 LAST PATH I1524
J 0
(-12270 5963);
DISPLAY 0.808511 (-12270 5963);
PAINT GREEN (-12270 5963);
DISPLAY INVISIBLE (-12270 5963);
FORCEADD TP_PIONT..1
(-12350 6750);
FORCEPROP 1 LAST $LOCATION TP199
J 0
(-12250 6750);
DISPLAY 0.808511 (-12250 6750);
PAINT GREEN (-12250 6750);
FORCEPROP 0 LAST CDS_LOCATION TP199
J 0
(-12250 6800);
DISPLAY 1.021277 (-12250 6800);
DISPLAY INVISIBLE (-12250 6800);
FORCEPROP 0 LAST $SEC 1
J 0
(-12250 6800);
DISPLAY 0.680851 (-12250 6800);
PAINT MONO (-12250 6800);
DISPLAY INVISIBLE (-12250 6800);
FORCEPROP 0 LAST CDS_SEC 1
J 0
(-12250 6800);
DISPLAY 1.021277 (-12250 6800);
DISPLAY INVISIBLE (-12250 6800);
FORCEPROP 0 LASTPIN (-12450 6750) $PN 1
J 2
(-12460 6760);
DISPLAY 0.680851 (-12460 6760);
PAINT MONO (-12460 6760);
FORCEPROP 1 LAST JEDEC_TYPE TP010CT020B030_PTH
J 0
(-12474 6850);
DISPLAY 0.000000 (-12474 6850);
PAINT GREEN (-12474 6850);
DISPLAY INVISIBLE (-12474 6850);
FORCEPROP 1 LAST BOM_IGNORE TRUE
J 0
(-12474 6850);
DISPLAY 0.000000 (-12474 6850);
PAINT GREEN (-12474 6850);
DISPLAY INVISIBLE (-12474 6850);
FORCEPROP 1 LAST CDS_LMAN_SYM_OUTLINE -50,50,50,-50
J 0
(-12350 6750);
DISPLAY 0.468085 (-12350 6750);
PAINT GREEN (-12350 6750);
DISPLAY INVISIBLE (-12350 6750);
FORCEPROP 2 LAST CDS_LIB cls
J 0
(-12350 6750);
DISPLAY INVISIBLE (-12350 6750);
FORCEPROP 1 LAST PATH I1527
J 0
(-12270 6863);
DISPLAY 0.808511 (-12270 6863);
PAINT GREEN (-12270 6863);
DISPLAY INVISIBLE (-12270 6863);
FORCEADD TP_PIONT..1
(-12350 6650);
FORCEPROP 1 LAST $LOCATION TP200
J 0
(-12250 6650);
DISPLAY 0.808511 (-12250 6650);
PAINT GREEN (-12250 6650);
FORCEPROP 0 LAST CDS_LOCATION TP200
J 0
(-12250 6700);
DISPLAY 1.021277 (-12250 6700);
DISPLAY INVISIBLE (-12250 6700);
FORCEPROP 0 LAST $SEC 1
J 0
(-12250 6700);
DISPLAY 0.680851 (-12250 6700);
PAINT MONO (-12250 6700);
DISPLAY INVISIBLE (-12250 6700);
FORCEPROP 0 LAST CDS_SEC 1
J 0
(-12250 6700);
DISPLAY 1.021277 (-12250 6700);
DISPLAY INVISIBLE (-12250 6700);
FORCEPROP 0 LASTPIN (-12450 6650) $PN 1
J 2
(-12460 6660);
DISPLAY 0.680851 (-12460 6660);
PAINT MONO (-12460 6660);
FORCEPROP 1 LAST JEDEC_TYPE TP010CT020B030_PTH
J 0
(-12474 6750);
DISPLAY 0.000000 (-12474 6750);
PAINT GREEN (-12474 6750);
DISPLAY INVISIBLE (-12474 6750);
FORCEPROP 1 LAST BOM_IGNORE TRUE
J 0
(-12474 6750);
DISPLAY 0.000000 (-12474 6750);
PAINT GREEN (-12474 6750);
DISPLAY INVISIBLE (-12474 6750);
FORCEPROP 1 LAST CDS_LMAN_SYM_OUTLINE -50,50,50,-50
J 0
(-12350 6650);
DISPLAY 0.468085 (-12350 6650);
PAINT GREEN (-12350 6650);
DISPLAY INVISIBLE (-12350 6650);
FORCEPROP 2 LAST CDS_LIB cls
J 0
(-12350 6650);
DISPLAY INVISIBLE (-12350 6650);
FORCEPROP 1 LAST PATH I1528
J 0
(-12270 6763);
DISPLAY 0.808511 (-12270 6763);
PAINT GREEN (-12270 6763);
DISPLAY INVISIBLE (-12270 6763);
FORCEADD TP_PIONT..1
(-12350 6350);
FORCEPROP 1 LAST $LOCATION TP201
J 0
(-12250 6350);
DISPLAY 0.808511 (-12250 6350);
PAINT GREEN (-12250 6350);
FORCEPROP 0 LAST CDS_LOCATION TP201
J 0
(-12250 6400);
DISPLAY 1.021277 (-12250 6400);
DISPLAY INVISIBLE (-12250 6400);
FORCEPROP 0 LAST $SEC 1
J 0
(-12250 6400);
DISPLAY 0.680851 (-12250 6400);
PAINT MONO (-12250 6400);
DISPLAY INVISIBLE (-12250 6400);
FORCEPROP 0 LAST CDS_SEC 1
J 0
(-12250 6400);
DISPLAY 1.021277 (-12250 6400);
DISPLAY INVISIBLE (-12250 6400);
FORCEPROP 0 LASTPIN (-12450 6350) $PN 1
J 2
(-12460 6360);
DISPLAY 0.680851 (-12460 6360);
PAINT MONO (-12460 6360);
FORCEPROP 2 LAST CDS_LIB cls
J 0
(-12350 6350);
DISPLAY INVISIBLE (-12350 6350);
FORCEPROP 1 LAST CDS_LMAN_SYM_OUTLINE -50,50,50,-50
J 0
(-12350 6350);
DISPLAY 0.468085 (-12350 6350);
PAINT GREEN (-12350 6350);
DISPLAY INVISIBLE (-12350 6350);
FORCEPROP 1 LAST BOM_IGNORE TRUE
J 0
(-12474 6450);
DISPLAY 0.000000 (-12474 6450);
PAINT GREEN (-12474 6450);
DISPLAY INVISIBLE (-12474 6450);
FORCEPROP 1 LAST JEDEC_TYPE TP010CT020B030_PTH
J 0
(-12474 6450);
DISPLAY 0.000000 (-12474 6450);
PAINT GREEN (-12474 6450);
DISPLAY INVISIBLE (-12474 6450);
FORCEPROP 1 LAST PATH I1529
J 0
(-12270 6463);
DISPLAY 0.808511 (-12270 6463);
PAINT GREEN (-12270 6463);
DISPLAY INVISIBLE (-12270 6463);
FORCEADD TP_PIONT..1
(-12350 6250);
FORCEPROP 1 LAST $LOCATION TP202
J 0
(-12250 6250);
DISPLAY 0.808511 (-12250 6250);
PAINT GREEN (-12250 6250);
FORCEPROP 0 LAST CDS_LOCATION TP202
J 0
(-12250 6300);
DISPLAY 1.021277 (-12250 6300);
DISPLAY INVISIBLE (-12250 6300);
FORCEPROP 0 LAST $SEC 1
J 0
(-12250 6300);
DISPLAY 0.680851 (-12250 6300);
PAINT MONO (-12250 6300);
DISPLAY INVISIBLE (-12250 6300);
FORCEPROP 0 LAST CDS_SEC 1
J 0
(-12250 6300);
DISPLAY 1.021277 (-12250 6300);
DISPLAY INVISIBLE (-12250 6300);
FORCEPROP 0 LASTPIN (-12450 6250) $PN 1
J 2
(-12460 6260);
DISPLAY 0.680851 (-12460 6260);
PAINT MONO (-12460 6260);
FORCEPROP 2 LAST CDS_LIB cls
J 0
(-12350 6250);
DISPLAY INVISIBLE (-12350 6250);
FORCEPROP 1 LAST CDS_LMAN_SYM_OUTLINE -50,50,50,-50
J 0
(-12350 6250);
DISPLAY 0.468085 (-12350 6250);
PAINT GREEN (-12350 6250);
DISPLAY INVISIBLE (-12350 6250);
FORCEPROP 1 LAST BOM_IGNORE TRUE
J 0
(-12474 6350);
DISPLAY 0.000000 (-12474 6350);
PAINT GREEN (-12474 6350);
DISPLAY INVISIBLE (-12474 6350);
FORCEPROP 1 LAST JEDEC_TYPE TP010CT020B030_PTH
J 0
(-12474 6350);
DISPLAY 0.000000 (-12474 6350);
PAINT GREEN (-12474 6350);
DISPLAY INVISIBLE (-12474 6350);
FORCEPROP 1 LAST PATH I1530
J 0
(-12270 6363);
DISPLAY 0.808511 (-12270 6363);
PAINT GREEN (-12270 6363);
DISPLAY INVISIBLE (-12270 6363);
FORCEADD OFFPAGE_BI..1
R 4
(-13300 5850);
FORCEPROP 2 LAST $XR0 13J5<> 
J 0
(-13519 5850);
DISPLAY 0.638298 (-13519 5850);
PAINT MONO (-13519 5850);
FORCEPROP 2 LAST CDS_LIB cls
J 0
(-13300 5850);
DISPLAY INVISIBLE (-13300 5850);
FORCEPROP 1 LAST CDS_LMAN_SYM_OUTLINE -50,50,50,-50
R 2
J 0
(-13300 5850);
DISPLAY 0.468085 (-13300 5850);
PAINT GREEN (-13300 5850);
DISPLAY INVISIBLE (-13300 5850);
FORCEPROP 1 LAST BODY_TYPE COMMENT
R 2
J 0
(-13310 5715);
DISPLAY 0.808511 (-13310 5715);
PAINT GREEN (-13310 5715);
DISPLAY INVISIBLE (-13310 5715);
FORCEPROP 1 LAST OFFPAGE TRUE
R 2
J 0
(-13310 5795);
DISPLAY 0.808511 (-13310 5795);
PAINT GREEN (-13310 5795);
DISPLAY INVISIBLE (-13310 5795);
FORCEPROP 2 LAST PATH I1531
J 0
(-13250 5950);
DISPLAY 1.021277 (-13250 5950);
DISPLAY INVISIBLE (-13250 5950);
FORCEADD OFFPAGE_BI..1
R 4
(-13300 6750);
FORCEPROP 2 LAST $XR0 13H5<> 
J 0
(-13519 6750);
DISPLAY 0.638298 (-13519 6750);
PAINT MONO (-13519 6750);
FORCEPROP 2 LAST CDS_LIB cls
J 0
(-13300 6750);
DISPLAY INVISIBLE (-13300 6750);
FORCEPROP 1 LAST CDS_LMAN_SYM_OUTLINE -50,50,50,-50
R 2
J 0
(-13300 6750);
DISPLAY 0.468085 (-13300 6750);
PAINT GREEN (-13300 6750);
DISPLAY INVISIBLE (-13300 6750);
FORCEPROP 1 LAST BODY_TYPE COMMENT
R 2
J 0
(-13310 6615);
DISPLAY 0.808511 (-13310 6615);
PAINT GREEN (-13310 6615);
DISPLAY INVISIBLE (-13310 6615);
FORCEPROP 1 LAST OFFPAGE TRUE
R 2
J 0
(-13310 6695);
DISPLAY 0.808511 (-13310 6695);
PAINT GREEN (-13310 6695);
DISPLAY INVISIBLE (-13310 6695);
FORCEPROP 2 LAST PATH I1534
J 0
(-13250 6850);
DISPLAY 1.021277 (-13250 6850);
DISPLAY INVISIBLE (-13250 6850);
FORCEADD OFFPAGE_BI..1
R 4
(-13300 6650);
FORCEPROP 2 LAST $XR0 13H5<> 
J 0
(-13519 6650);
DISPLAY 0.638298 (-13519 6650);
PAINT MONO (-13519 6650);
FORCEPROP 2 LAST CDS_LIB cls
J 0
(-13300 6650);
DISPLAY INVISIBLE (-13300 6650);
FORCEPROP 1 LAST CDS_LMAN_SYM_OUTLINE -50,50,50,-50
R 2
J 0
(-13300 6650);
DISPLAY 0.468085 (-13300 6650);
PAINT GREEN (-13300 6650);
DISPLAY INVISIBLE (-13300 6650);
FORCEPROP 1 LAST BODY_TYPE COMMENT
R 2
J 0
(-13310 6515);
DISPLAY 0.808511 (-13310 6515);
PAINT GREEN (-13310 6515);
DISPLAY INVISIBLE (-13310 6515);
FORCEPROP 1 LAST OFFPAGE TRUE
R 2
J 0
(-13310 6595);
DISPLAY 0.808511 (-13310 6595);
PAINT GREEN (-13310 6595);
DISPLAY INVISIBLE (-13310 6595);
FORCEPROP 2 LAST PATH I1535
J 0
(-13250 6750);
DISPLAY 1.021277 (-13250 6750);
DISPLAY INVISIBLE (-13250 6750);
FORCEADD OFFPAGE_BI..1
R 4
(-13300 6350);
FORCEPROP 2 LAST $XR0 13H5<> 
J 0
(-13519 6350);
DISPLAY 0.638298 (-13519 6350);
PAINT MONO (-13519 6350);
FORCEPROP 2 LAST CDS_LIB cls
J 0
(-13300 6350);
DISPLAY INVISIBLE (-13300 6350);
FORCEPROP 1 LAST CDS_LMAN_SYM_OUTLINE -50,50,50,-50
R 2
J 0
(-13300 6350);
DISPLAY 0.468085 (-13300 6350);
PAINT GREEN (-13300 6350);
DISPLAY INVISIBLE (-13300 6350);
FORCEPROP 1 LAST BODY_TYPE COMMENT
R 2
J 0
(-13310 6215);
DISPLAY 0.808511 (-13310 6215);
PAINT GREEN (-13310 6215);
DISPLAY INVISIBLE (-13310 6215);
FORCEPROP 1 LAST OFFPAGE TRUE
R 2
J 0
(-13310 6295);
DISPLAY 0.808511 (-13310 6295);
PAINT GREEN (-13310 6295);
DISPLAY INVISIBLE (-13310 6295);
FORCEPROP 2 LAST PATH I1536
J 0
(-13250 6450);
DISPLAY 1.021277 (-13250 6450);
DISPLAY INVISIBLE (-13250 6450);
FORCEADD OFFPAGE_BI..1
R 4
(-13300 6250);
FORCEPROP 2 LAST $XR0 13J5<> 
J 0
(-13519 6250);
DISPLAY 0.638298 (-13519 6250);
PAINT MONO (-13519 6250);
FORCEPROP 2 LAST CDS_LIB cls
J 0
(-13300 6250);
DISPLAY INVISIBLE (-13300 6250);
FORCEPROP 1 LAST CDS_LMAN_SYM_OUTLINE -50,50,50,-50
R 2
J 0
(-13300 6250);
DISPLAY 0.468085 (-13300 6250);
PAINT GREEN (-13300 6250);
DISPLAY INVISIBLE (-13300 6250);
FORCEPROP 1 LAST BODY_TYPE COMMENT
R 2
J 0
(-13310 6115);
DISPLAY 0.808511 (-13310 6115);
PAINT GREEN (-13310 6115);
DISPLAY INVISIBLE (-13310 6115);
FORCEPROP 1 LAST OFFPAGE TRUE
R 2
J 0
(-13310 6195);
DISPLAY 0.808511 (-13310 6195);
PAINT GREEN (-13310 6195);
DISPLAY INVISIBLE (-13310 6195);
FORCEPROP 2 LAST PATH I1537
J 0
(-13250 6350);
DISPLAY 1.021277 (-13250 6350);
DISPLAY INVISIBLE (-13250 6350);
FORCEADD OFFPAGE_BI..1
R 4
(-13300 5950);
FORCEPROP 2 LAST $XR0 13J5<> 
J 0
(-13519 5950);
DISPLAY 0.638298 (-13519 5950);
PAINT MONO (-13519 5950);
FORCEPROP 2 LAST CDS_LIB cls
J 0
(-13300 5950);
DISPLAY INVISIBLE (-13300 5950);
FORCEPROP 1 LAST CDS_LMAN_SYM_OUTLINE -50,50,50,-50
R 2
J 0
(-13300 5950);
DISPLAY 0.468085 (-13300 5950);
PAINT GREEN (-13300 5950);
DISPLAY INVISIBLE (-13300 5950);
FORCEPROP 1 LAST BODY_TYPE COMMENT
R 2
J 0
(-13310 5815);
DISPLAY 0.808511 (-13310 5815);
PAINT GREEN (-13310 5815);
DISPLAY INVISIBLE (-13310 5815);
FORCEPROP 1 LAST OFFPAGE TRUE
R 2
J 0
(-13310 5895);
DISPLAY 0.808511 (-13310 5895);
PAINT GREEN (-13310 5895);
DISPLAY INVISIBLE (-13310 5895);
FORCEPROP 2 LAST PATH I1538
J 0
(-13250 6050);
DISPLAY 1.021277 (-13250 6050);
DISPLAY INVISIBLE (-13250 6050);
FORCEADD GND_SG..1
(-12900 1650);
FORCEPROP 3 LASTPIN (-12850 1700) SIG_NAME SG\g
J 0
(-12840 1710);
DISPLAY 0.659574 (-12840 1710);
PAINT MONO (-12840 1710);
DISPLAY INVISIBLE (-12840 1710);
FORCEPROP 0 LAST VOLTAGE 0
J 0
(-12800 1650);
DISPLAY 1.021277 (-12800 1650);
FORCEPROP 1 LAST HDL_POWER SG
J 1
(-12845 1555);
DISPLAY 0.808511 (-12845 1555);
PAINT GREEN (-12845 1555);
FORCEPROP 1 LAST PATH I1540
J 0
(-12865 1650);
DISPLAY 0.808511 (-12865 1650);
PAINT GREEN (-12865 1650);
DISPLAY INVISIBLE (-12865 1650);
FORCEPROP 1 LAST CDS_LMAN_SYM_OUTLINE 0,0,100,-50
J 0
(-12900 1650);
DISPLAY 0.468085 (-12900 1650);
PAINT GREEN (-12900 1650);
DISPLAY INVISIBLE (-12900 1650);
FORCEPROP 2 LAST CDS_LIB cls
J 0
(-12900 1650);
DISPLAY INVISIBLE (-12900 1650);
FORCEPROP 1 LAST BODY_TYPE PLUMBING
J 0
(-12885 1635);
DISPLAY 0.808511 (-12885 1635);
PAINT GREEN (-12885 1635);
DISPLAY INVISIBLE (-12885 1635);
FORCEADD VCC..1
(-13000 4300);
FORCEPROP 3 LASTPIN (-12950 4250) SIG_NAME XP3R3V_FPGA\g
J 0
(-12940 4260);
DISPLAY 0.659574 (-12940 4260);
PAINT MONO (-12940 4260);
DISPLAY INVISIBLE (-12940 4260);
FORCEPROP 1 LAST HDL_POWER XP3R3V_FPGA
J 1
(-12945 4355);
DISPLAY 1.021277 (-12945 4355);
PAINT GREEN (-12945 4355);
FORCEPROP 0 LAST VOLTAGE 3.3V
J 0
(-13200 4400);
DISPLAY 1.021277 (-13200 4400);
DISPLAY BOTH (-13200 4400);
FORCEPROP 2 LAST CDS_LIB cls
J 0
(-13000 4300);
DISPLAY INVISIBLE (-13000 4300);
FORCEPROP 1 LAST CDS_LMAN_SYM_OUTLINE -250,250,250,-250
J 0
(-13000 4300);
DISPLAY 0.468085 (-13000 4300);
PAINT GREEN (-13000 4300);
DISPLAY INVISIBLE (-13000 4300);
FORCEPROP 1 LAST PATH I1541
J 0
(-12965 4390);
DISPLAY 0.808511 (-12965 4390);
PAINT GREEN (-12965 4390);
DISPLAY INVISIBLE (-12965 4390);
FORCEPROP 1 LAST BODY_TYPE PLUMBING
J 0
(-13045 4257);
DISPLAY 0.340426 (-13045 4257);
PAINT GREEN (-13045 4257);
DISPLAY INVISIBLE (-13045 4257);
FORCEADD RESISTOR..2
R 1
(-12350 4000);
FORCEPROP 1 LAST $LOCATION R171
J 0
(-12700 4000);
DISPLAY 1.212766 (-12700 4000);
PAINT GREEN (-12700 4000);
FORCEPROP 0 LAST CDS_LOCATION R171
R 1
J 0
(-12100 4100);
DISPLAY 1.021277 (-12100 4100);
DISPLAY INVISIBLE (-12100 4100);
FORCEPROP 0 LAST $SEC 1
R 1
J 0
(-12100 4100);
DISPLAY 0.680851 (-12100 4100);
PAINT MONO (-12100 4100);
DISPLAY INVISIBLE (-12100 4100);
FORCEPROP 0 LAST CDS_SEC 1
R 1
J 0
(-12100 4100);
DISPLAY 1.021277 (-12100 4100);
DISPLAY INVISIBLE (-12100 4100);
FORCEPROP 0 LASTPIN (-12450 4000) $PN 1
J 2
(-12460 4010);
DISPLAY 0.680851 (-12460 4010);
PAINT MONO (-12460 4010);
FORCEPROP 0 LASTPIN (-12200 4000) $PN 2
J 0
(-12190 4010);
DISPLAY 0.680851 (-12190 4010);
PAINT MONO (-12190 4010);
FORCEPROP 0 LAST NO_ASSY TRUE
J 0
(-12450 3950);
DISPLAY 0.808511 (-12450 3950);
DISPLAY BOTH (-12450 3950);
FORCEPROP 0 LAST PACKAGE 0402
J 0
(-12400 4050);
DISPLAY 0.808511 (-12400 4050);
FORCEPROP 1 LAST VALUE 4.7KOHM
J 0
(-12100 4000);
DISPLAY 1.212766 (-12100 4000);
PAINT GREEN (-12100 4000);
FORCEPROP 1 LAST TOLERANCE 1%
R 1
J 0
(-12605 3803);
DISPLAY 1.212766 (-12605 3803);
PAINT GREEN (-12605 3803);
DISPLAY INVISIBLE (-12605 3803);
FORCEPROP 1 LAST CLS_PN G155-14701-01
R 1
J 0
(-12550 3864);
DISPLAY 1.212766 (-12550 3864);
PAINT GREEN (-12550 3864);
DISPLAY INVISIBLE (-12550 3864);
FORCEPROP 1 LAST CDS_LMAN_SYM_OUTLINE -50,50,50,-100
R 1
J 0
(-12350 4000);
DISPLAY 0.468085 (-12350 4000);
PAINT GREEN (-12350 4000);
DISPLAY INVISIBLE (-12350 4000);
FORCEPROP 2 LAST CDS_LIB passive
J 0
(-12350 4000);
DISPLAY INVISIBLE (-12350 4000);
FORCEPROP 1 LAST PATH I1542
R 1
J 0
(-12455 3803);
DISPLAY 1.212766 (-12455 3803);
PAINT GREEN (-12455 3803);
DISPLAY INVISIBLE (-12455 3803);
FORCEADD RESISTOR..2
R 1
(-12350 3700);
FORCEPROP 1 LAST $LOCATION R173
J 0
(-12700 3700);
DISPLAY 1.212766 (-12700 3700);
PAINT GREEN (-12700 3700);
FORCEPROP 0 LAST CDS_LOCATION R173
R 1
J 0
(-12100 3800);
DISPLAY 1.021277 (-12100 3800);
DISPLAY INVISIBLE (-12100 3800);
FORCEPROP 0 LAST $SEC 1
R 1
J 0
(-12100 3800);
DISPLAY 0.680851 (-12100 3800);
PAINT MONO (-12100 3800);
DISPLAY INVISIBLE (-12100 3800);
FORCEPROP 0 LAST CDS_SEC 1
R 1
J 0
(-12100 3800);
DISPLAY 1.021277 (-12100 3800);
DISPLAY INVISIBLE (-12100 3800);
FORCEPROP 0 LASTPIN (-12450 3700) $PN 1
J 2
(-12460 3710);
DISPLAY 0.680851 (-12460 3710);
PAINT MONO (-12460 3710);
FORCEPROP 0 LASTPIN (-12200 3700) $PN 2
J 0
(-12190 3710);
DISPLAY 0.680851 (-12190 3710);
PAINT MONO (-12190 3710);
FORCEPROP 1 LAST VALUE 4.7KOHM
J 0
(-12100 3700);
DISPLAY 1.212766 (-12100 3700);
PAINT GREEN (-12100 3700);
FORCEPROP 0 LAST NO_ASSY TRUE
J 0
(-12450 3650);
DISPLAY 0.808511 (-12450 3650);
DISPLAY BOTH (-12450 3650);
FORCEPROP 0 LAST PACKAGE 0402
J 0
(-12400 3750);
DISPLAY 0.808511 (-12400 3750);
FORCEPROP 1 LAST PATH I1544
R 1
J 0
(-12455 3503);
DISPLAY 1.212766 (-12455 3503);
PAINT GREEN (-12455 3503);
DISPLAY INVISIBLE (-12455 3503);
FORCEPROP 1 LAST TOLERANCE 1%
R 1
J 0
(-12605 3503);
DISPLAY 1.212766 (-12605 3503);
PAINT GREEN (-12605 3503);
DISPLAY INVISIBLE (-12605 3503);
FORCEPROP 1 LAST CLS_PN G155-14701-01
R 1
J 0
(-12550 3564);
DISPLAY 1.212766 (-12550 3564);
PAINT GREEN (-12550 3564);
DISPLAY INVISIBLE (-12550 3564);
FORCEPROP 1 LAST CDS_LMAN_SYM_OUTLINE -50,50,50,-100
R 1
J 0
(-12350 3700);
DISPLAY 0.468085 (-12350 3700);
PAINT GREEN (-12350 3700);
DISPLAY INVISIBLE (-12350 3700);
FORCEPROP 2 LAST CDS_LIB passive
J 0
(-12350 3700);
DISPLAY INVISIBLE (-12350 3700);
FORCEADD RESISTOR..2
R 1
(-12350 3400);
FORCEPROP 1 LAST $LOCATION R284
J 0
(-12700 3400);
DISPLAY 1.212766 (-12700 3400);
PAINT GREEN (-12700 3400);
FORCEPROP 0 LAST CDS_LOCATION R284
R 1
J 0
(-12100 3500);
DISPLAY 1.021277 (-12100 3500);
DISPLAY INVISIBLE (-12100 3500);
FORCEPROP 0 LAST $SEC 1
R 1
J 0
(-12100 3500);
DISPLAY 0.680851 (-12100 3500);
PAINT MONO (-12100 3500);
DISPLAY INVISIBLE (-12100 3500);
FORCEPROP 0 LAST CDS_SEC 1
R 1
J 0
(-12100 3500);
DISPLAY 1.021277 (-12100 3500);
DISPLAY INVISIBLE (-12100 3500);
FORCEPROP 0 LASTPIN (-12450 3400) $PN 1
J 2
(-12460 3410);
DISPLAY 0.680851 (-12460 3410);
PAINT MONO (-12460 3410);
FORCEPROP 0 LASTPIN (-12200 3400) $PN 2
J 0
(-12190 3410);
DISPLAY 0.680851 (-12190 3410);
PAINT MONO (-12190 3410);
FORCEPROP 1 LAST VALUE 4.7KOHM
J 0
(-12100 3400);
DISPLAY 1.212766 (-12100 3400);
PAINT GREEN (-12100 3400);
FORCEPROP 0 LAST PACKAGE 0402
J 0
(-12400 3450);
DISPLAY 0.808511 (-12400 3450);
FORCEPROP 0 LAST NO_ASSY TRUE
J 0
(-12450 3350);
DISPLAY 0.808511 (-12450 3350);
DISPLAY BOTH (-12450 3350);
FORCEPROP 2 LAST CDS_LIB passive
J 0
(-12350 3400);
DISPLAY INVISIBLE (-12350 3400);
FORCEPROP 1 LAST CDS_LMAN_SYM_OUTLINE -50,50,50,-100
R 1
J 0
(-12350 3400);
DISPLAY 0.468085 (-12350 3400);
PAINT GREEN (-12350 3400);
DISPLAY INVISIBLE (-12350 3400);
FORCEPROP 1 LAST CLS_PN G155-14701-01
R 1
J 0
(-12550 3264);
DISPLAY 1.212766 (-12550 3264);
PAINT GREEN (-12550 3264);
DISPLAY INVISIBLE (-12550 3264);
FORCEPROP 1 LAST TOLERANCE 1%
R 1
J 0
(-12605 3203);
DISPLAY 1.212766 (-12605 3203);
PAINT GREEN (-12605 3203);
DISPLAY INVISIBLE (-12605 3203);
FORCEPROP 1 LAST PATH I1547
R 1
J 0
(-12455 3203);
DISPLAY 1.212766 (-12455 3203);
PAINT GREEN (-12455 3203);
DISPLAY INVISIBLE (-12455 3203);
FORCEADD RESISTOR..2
R 1
(-12350 3100);
FORCEPROP 1 LAST $LOCATION R286
J 0
(-12700 3100);
DISPLAY 1.212766 (-12700 3100);
PAINT GREEN (-12700 3100);
FORCEPROP 0 LAST CDS_LOCATION R286
R 1
J 0
(-12100 3200);
DISPLAY 1.021277 (-12100 3200);
DISPLAY INVISIBLE (-12100 3200);
FORCEPROP 0 LAST $SEC 1
R 1
J 0
(-12100 3200);
DISPLAY 0.680851 (-12100 3200);
PAINT MONO (-12100 3200);
DISPLAY INVISIBLE (-12100 3200);
FORCEPROP 0 LAST CDS_SEC 1
R 1
J 0
(-12100 3200);
DISPLAY 1.021277 (-12100 3200);
DISPLAY INVISIBLE (-12100 3200);
FORCEPROP 0 LASTPIN (-12450 3100) $PN 1
J 2
(-12460 3110);
DISPLAY 0.680851 (-12460 3110);
PAINT MONO (-12460 3110);
FORCEPROP 0 LASTPIN (-12200 3100) $PN 2
J 0
(-12190 3110);
DISPLAY 0.680851 (-12190 3110);
PAINT MONO (-12190 3110);
FORCEPROP 1 LAST VALUE 4.7KOHM
J 0
(-12100 3100);
DISPLAY 1.212766 (-12100 3100);
PAINT GREEN (-12100 3100);
FORCEPROP 0 LAST NO_ASSY TRUE
J 0
(-12450 3050);
DISPLAY 0.808511 (-12450 3050);
DISPLAY BOTH (-12450 3050);
FORCEPROP 0 LAST PACKAGE 0402
J 0
(-12400 3150);
DISPLAY 0.808511 (-12400 3150);
FORCEPROP 1 LAST PATH I1549
R 1
J 0
(-12455 2903);
DISPLAY 1.212766 (-12455 2903);
PAINT GREEN (-12455 2903);
DISPLAY INVISIBLE (-12455 2903);
FORCEPROP 2 LAST CDS_LIB passive
J 0
(-12350 3100);
DISPLAY INVISIBLE (-12350 3100);
FORCEPROP 1 LAST CDS_LMAN_SYM_OUTLINE -50,50,50,-100
R 1
J 0
(-12350 3100);
DISPLAY 0.468085 (-12350 3100);
PAINT GREEN (-12350 3100);
DISPLAY INVISIBLE (-12350 3100);
FORCEPROP 1 LAST CLS_PN G155-14701-01
R 1
J 0
(-12550 2964);
DISPLAY 1.212766 (-12550 2964);
PAINT GREEN (-12550 2964);
DISPLAY INVISIBLE (-12550 2964);
FORCEPROP 1 LAST TOLERANCE 1%
R 1
J 0
(-12605 2903);
DISPLAY 1.212766 (-12605 2903);
PAINT GREEN (-12605 2903);
DISPLAY INVISIBLE (-12605 2903);
FORCEADD RESISTOR..2
R 1
(-12350 1900);
FORCEPROP 1 LAST $LOCATION R328
J 0
(-12700 1900);
DISPLAY 1.212766 (-12700 1900);
PAINT GREEN (-12700 1900);
FORCEPROP 0 LAST CDS_LOCATION R328
R 1
J 0
(-12100 2000);
DISPLAY 1.021277 (-12100 2000);
DISPLAY INVISIBLE (-12100 2000);
FORCEPROP 0 LAST $SEC 1
R 1
J 0
(-12100 2000);
DISPLAY 0.680851 (-12100 2000);
PAINT MONO (-12100 2000);
DISPLAY INVISIBLE (-12100 2000);
FORCEPROP 0 LAST CDS_SEC 1
R 1
J 0
(-12100 2000);
DISPLAY 1.021277 (-12100 2000);
DISPLAY INVISIBLE (-12100 2000);
FORCEPROP 0 LASTPIN (-12450 1900) $PN 1
J 2
(-12460 1910);
DISPLAY 0.680851 (-12460 1910);
PAINT MONO (-12460 1910);
FORCEPROP 0 LASTPIN (-12200 1900) $PN 2
J 0
(-12190 1910);
DISPLAY 0.680851 (-12190 1910);
PAINT MONO (-12190 1910);
FORCEPROP 0 LAST NO_ASSY TRUE
J 0
(-12450 1850);
DISPLAY 0.808511 (-12450 1850);
DISPLAY BOTH (-12450 1850);
FORCEPROP 0 LAST PACKAGE 0402
J 0
(-12400 1950);
DISPLAY 0.808511 (-12400 1950);
FORCEPROP 1 LAST VALUE 4.7KOHM
J 0
(-12100 1900);
DISPLAY 1.212766 (-12100 1900);
PAINT GREEN (-12100 1900);
FORCEPROP 1 LAST PATH I1550
R 1
J 0
(-12455 1703);
DISPLAY 1.212766 (-12455 1703);
PAINT GREEN (-12455 1703);
DISPLAY INVISIBLE (-12455 1703);
FORCEPROP 1 LAST TOLERANCE 1%
R 1
J 0
(-12605 1703);
DISPLAY 1.212766 (-12605 1703);
PAINT GREEN (-12605 1703);
DISPLAY INVISIBLE (-12605 1703);
FORCEPROP 1 LAST CLS_PN G155-14701-01
R 1
J 0
(-12550 1764);
DISPLAY 1.212766 (-12550 1764);
PAINT GREEN (-12550 1764);
DISPLAY INVISIBLE (-12550 1764);
FORCEPROP 1 LAST CDS_LMAN_SYM_OUTLINE -50,50,50,-100
R 1
J 0
(-12350 1900);
DISPLAY 0.468085 (-12350 1900);
PAINT GREEN (-12350 1900);
DISPLAY INVISIBLE (-12350 1900);
FORCEPROP 2 LAST CDS_LIB passive
J 0
(-12350 1900);
DISPLAY INVISIBLE (-12350 1900);
FORCEADD RESISTOR..2
R 1
(-12350 2200);
FORCEPROP 1 LAST $LOCATION R326
J 0
(-12700 2200);
DISPLAY 1.212766 (-12700 2200);
PAINT GREEN (-12700 2200);
FORCEPROP 0 LAST CDS_LOCATION R326
R 1
J 0
(-12100 2300);
DISPLAY 1.021277 (-12100 2300);
DISPLAY INVISIBLE (-12100 2300);
FORCEPROP 0 LAST $SEC 1
R 1
J 0
(-12100 2300);
DISPLAY 0.680851 (-12100 2300);
PAINT MONO (-12100 2300);
DISPLAY INVISIBLE (-12100 2300);
FORCEPROP 0 LAST CDS_SEC 1
R 1
J 0
(-12100 2300);
DISPLAY 1.021277 (-12100 2300);
DISPLAY INVISIBLE (-12100 2300);
FORCEPROP 0 LASTPIN (-12450 2200) $PN 1
J 2
(-12460 2210);
DISPLAY 0.680851 (-12460 2210);
PAINT MONO (-12460 2210);
FORCEPROP 0 LASTPIN (-12200 2200) $PN 2
J 0
(-12190 2210);
DISPLAY 0.680851 (-12190 2210);
PAINT MONO (-12190 2210);
FORCEPROP 1 LAST VALUE 4.7KOHM
J 0
(-12100 2200);
DISPLAY 1.212766 (-12100 2200);
PAINT GREEN (-12100 2200);
FORCEPROP 0 LAST NO_ASSY TRUE
J 0
(-12450 2150);
DISPLAY 0.808511 (-12450 2150);
DISPLAY BOTH (-12450 2150);
FORCEPROP 0 LAST PACKAGE 0402
J 0
(-12400 2250);
DISPLAY 0.808511 (-12400 2250);
FORCEPROP 1 LAST PATH I1552
R 1
J 0
(-12455 2003);
DISPLAY 1.212766 (-12455 2003);
PAINT GREEN (-12455 2003);
DISPLAY INVISIBLE (-12455 2003);
FORCEPROP 1 LAST TOLERANCE 1%
R 1
J 0
(-12605 2003);
DISPLAY 1.212766 (-12605 2003);
PAINT GREEN (-12605 2003);
DISPLAY INVISIBLE (-12605 2003);
FORCEPROP 1 LAST CLS_PN G155-14701-01
R 1
J 0
(-12550 2064);
DISPLAY 1.212766 (-12550 2064);
PAINT GREEN (-12550 2064);
DISPLAY INVISIBLE (-12550 2064);
FORCEPROP 1 LAST CDS_LMAN_SYM_OUTLINE -50,50,50,-100
R 1
J 0
(-12350 2200);
DISPLAY 0.468085 (-12350 2200);
PAINT GREEN (-12350 2200);
DISPLAY INVISIBLE (-12350 2200);
FORCEPROP 2 LAST CDS_LIB passive
J 0
(-12350 2200);
DISPLAY INVISIBLE (-12350 2200);
FORCEADD RESISTOR..2
R 1
(-12350 2800);
FORCEPROP 1 LAST $LOCATION R293
J 0
(-12700 2800);
DISPLAY 1.212766 (-12700 2800);
PAINT GREEN (-12700 2800);
FORCEPROP 0 LAST CDS_LOCATION R293
R 1
J 0
(-12100 2900);
DISPLAY 1.021277 (-12100 2900);
DISPLAY INVISIBLE (-12100 2900);
FORCEPROP 0 LAST $SEC 1
R 1
J 0
(-12100 2900);
DISPLAY 0.680851 (-12100 2900);
PAINT MONO (-12100 2900);
DISPLAY INVISIBLE (-12100 2900);
FORCEPROP 0 LAST CDS_SEC 1
R 1
J 0
(-12100 2900);
DISPLAY 1.021277 (-12100 2900);
DISPLAY INVISIBLE (-12100 2900);
FORCEPROP 0 LASTPIN (-12450 2800) $PN 1
J 2
(-12460 2810);
DISPLAY 0.680851 (-12460 2810);
PAINT MONO (-12460 2810);
FORCEPROP 0 LASTPIN (-12200 2800) $PN 2
J 0
(-12190 2810);
DISPLAY 0.680851 (-12190 2810);
PAINT MONO (-12190 2810);
FORCEPROP 1 LAST VALUE 4.7KOHM
J 0
(-12100 2800);
DISPLAY 1.212766 (-12100 2800);
PAINT GREEN (-12100 2800);
FORCEPROP 0 LAST NO_ASSY TRUE
J 0
(-12450 2750);
DISPLAY 0.808511 (-12450 2750);
DISPLAY BOTH (-12450 2750);
FORCEPROP 0 LAST PACKAGE 0402
J 0
(-12400 2850);
DISPLAY 0.808511 (-12400 2850);
FORCEPROP 1 LAST PATH I1555
R 1
J 0
(-12455 2603);
DISPLAY 1.212766 (-12455 2603);
PAINT GREEN (-12455 2603);
DISPLAY INVISIBLE (-12455 2603);
FORCEPROP 2 LAST CDS_LIB passive
J 0
(-12350 2800);
DISPLAY INVISIBLE (-12350 2800);
FORCEPROP 1 LAST CDS_LMAN_SYM_OUTLINE -50,50,50,-100
R 1
J 0
(-12350 2800);
DISPLAY 0.468085 (-12350 2800);
PAINT GREEN (-12350 2800);
DISPLAY INVISIBLE (-12350 2800);
FORCEPROP 1 LAST CLS_PN G155-14701-01
R 1
J 0
(-12550 2664);
DISPLAY 1.212766 (-12550 2664);
PAINT GREEN (-12550 2664);
DISPLAY INVISIBLE (-12550 2664);
FORCEPROP 1 LAST TOLERANCE 1%
R 1
J 0
(-12605 2603);
DISPLAY 1.212766 (-12605 2603);
PAINT GREEN (-12605 2603);
DISPLAY INVISIBLE (-12605 2603);
FORCEADD RESISTOR..2
R 1
(-12350 2500);
FORCEPROP 1 LAST $LOCATION R309
J 0
(-12700 2500);
DISPLAY 1.212766 (-12700 2500);
PAINT GREEN (-12700 2500);
FORCEPROP 0 LAST CDS_LOCATION R309
R 1
J 0
(-12100 2600);
DISPLAY 1.021277 (-12100 2600);
DISPLAY INVISIBLE (-12100 2600);
FORCEPROP 0 LAST $SEC 1
R 1
J 0
(-12100 2600);
DISPLAY 0.680851 (-12100 2600);
PAINT MONO (-12100 2600);
DISPLAY INVISIBLE (-12100 2600);
FORCEPROP 0 LAST CDS_SEC 1
R 1
J 0
(-12100 2600);
DISPLAY 1.021277 (-12100 2600);
DISPLAY INVISIBLE (-12100 2600);
FORCEPROP 0 LASTPIN (-12450 2500) $PN 1
J 2
(-12460 2510);
DISPLAY 0.680851 (-12460 2510);
PAINT MONO (-12460 2510);
FORCEPROP 0 LASTPIN (-12200 2500) $PN 2
J 0
(-12190 2510);
DISPLAY 0.680851 (-12190 2510);
PAINT MONO (-12190 2510);
FORCEPROP 1 LAST VALUE 4.7KOHM
J 0
(-12100 2500);
DISPLAY 1.212766 (-12100 2500);
PAINT GREEN (-12100 2500);
FORCEPROP 0 LAST NO_ASSY TRUE
J 0
(-12450 2450);
DISPLAY 0.808511 (-12450 2450);
DISPLAY BOTH (-12450 2450);
FORCEPROP 0 LAST PACKAGE 0402
J 0
(-12400 2550);
DISPLAY 0.808511 (-12400 2550);
FORCEPROP 1 LAST PATH I1557
R 1
J 0
(-12455 2303);
DISPLAY 1.212766 (-12455 2303);
PAINT GREEN (-12455 2303);
DISPLAY INVISIBLE (-12455 2303);
FORCEPROP 2 LAST CDS_LIB passive
J 0
(-12350 2500);
DISPLAY INVISIBLE (-12350 2500);
FORCEPROP 1 LAST CDS_LMAN_SYM_OUTLINE -50,50,50,-100
R 1
J 0
(-12350 2500);
DISPLAY 0.468085 (-12350 2500);
PAINT GREEN (-12350 2500);
DISPLAY INVISIBLE (-12350 2500);
FORCEPROP 1 LAST CLS_PN G155-14701-01
R 1
J 0
(-12550 2364);
DISPLAY 1.212766 (-12550 2364);
PAINT GREEN (-12550 2364);
DISPLAY INVISIBLE (-12550 2364);
FORCEPROP 1 LAST TOLERANCE 1%
R 1
J 0
(-12605 2303);
DISPLAY 1.212766 (-12605 2303);
PAINT GREEN (-12605 2303);
DISPLAY INVISIBLE (-12605 2303);
FORCEADD OFFPAGE_BI..1
R 6
(-10800 4100);
FORCEPROP 2 LAST $XR1 25J12<> 
J 0
(-10530 4100);
DISPLAY 0.638298 (-10530 4100);
PAINT MONO (-10530 4100);
FORCEPROP 2 LAST $XR0 12E5<> 
J 0
(-10740 4100);
DISPLAY 0.638298 (-10740 4100);
PAINT MONO (-10740 4100);
FORCEPROP 2 LAST CDS_LIB cls
J 0
(-10800 4100);
DISPLAY INVISIBLE (-10800 4100);
FORCEPROP 1 LAST CDS_LMAN_SYM_OUTLINE -50,50,50,-50
J 0
(-10800 4100);
DISPLAY 0.468085 (-10800 4100);
PAINT GREEN (-10800 4100);
DISPLAY INVISIBLE (-10800 4100);
FORCEPROP 1 LAST BODY_TYPE COMMENT
J 0
(-10790 3927);
DISPLAY 0.808511 (-10790 3927);
PAINT GREEN (-10790 3927);
DISPLAY INVISIBLE (-10790 3927);
FORCEPROP 1 LAST OFFPAGE TRUE
J 0
(-10790 4007);
DISPLAY 0.808511 (-10790 4007);
PAINT GREEN (-10790 4007);
DISPLAY INVISIBLE (-10790 4007);
FORCEPROP 2 LAST PATH I1562
J 0
(-10750 4200);
DISPLAY 1.021277 (-10750 4200);
DISPLAY INVISIBLE (-10750 4200);
FORCEADD OFFPAGE_BI..1
R 6
(-10800 3800);
FORCEPROP 2 LAST $XR0 12E5<> 
J 0
(-10740 3800);
DISPLAY 0.638298 (-10740 3800);
PAINT MONO (-10740 3800);
FORCEPROP 2 LAST $XR1 25J12<> 
J 0
(-10530 3800);
DISPLAY 0.638298 (-10530 3800);
PAINT MONO (-10530 3800);
FORCEPROP 2 LAST CDS_LIB cls
J 0
(-10800 3800);
DISPLAY INVISIBLE (-10800 3800);
FORCEPROP 1 LAST CDS_LMAN_SYM_OUTLINE -50,50,50,-50
J 0
(-10800 3800);
DISPLAY 0.468085 (-10800 3800);
PAINT GREEN (-10800 3800);
DISPLAY INVISIBLE (-10800 3800);
FORCEPROP 1 LAST BODY_TYPE COMMENT
J 0
(-10790 3627);
DISPLAY 0.808511 (-10790 3627);
PAINT GREEN (-10790 3627);
DISPLAY INVISIBLE (-10790 3627);
FORCEPROP 1 LAST OFFPAGE TRUE
J 0
(-10790 3707);
DISPLAY 0.808511 (-10790 3707);
PAINT GREEN (-10790 3707);
DISPLAY INVISIBLE (-10790 3707);
FORCEPROP 2 LAST PATH I1563
J 0
(-10750 3900);
DISPLAY 1.021277 (-10750 3900);
DISPLAY INVISIBLE (-10750 3900);
FORCEADD OFFPAGE_BI..1
R 6
(-10800 3500);
FORCEPROP 2 LAST $XR1 25J12<> 
J 0
(-10530 3500);
DISPLAY 0.638298 (-10530 3500);
PAINT MONO (-10530 3500);
FORCEPROP 2 LAST $XR0 12E5<> 
J 0
(-10740 3500);
DISPLAY 0.638298 (-10740 3500);
PAINT MONO (-10740 3500);
FORCEPROP 2 LAST CDS_LIB cls
J 0
(-10800 3500);
DISPLAY INVISIBLE (-10800 3500);
FORCEPROP 1 LAST CDS_LMAN_SYM_OUTLINE -50,50,50,-50
J 0
(-10800 3500);
DISPLAY 0.468085 (-10800 3500);
PAINT GREEN (-10800 3500);
DISPLAY INVISIBLE (-10800 3500);
FORCEPROP 1 LAST BODY_TYPE COMMENT
J 0
(-10790 3327);
DISPLAY 0.808511 (-10790 3327);
PAINT GREEN (-10790 3327);
DISPLAY INVISIBLE (-10790 3327);
FORCEPROP 1 LAST OFFPAGE TRUE
J 0
(-10790 3407);
DISPLAY 0.808511 (-10790 3407);
PAINT GREEN (-10790 3407);
DISPLAY INVISIBLE (-10790 3407);
FORCEPROP 2 LAST PATH I1564
J 0
(-10750 3600);
DISPLAY 1.021277 (-10750 3600);
DISPLAY INVISIBLE (-10750 3600);
FORCEADD OFFPAGE_BI..1
R 6
(-10800 3200);
FORCEPROP 2 LAST $XR1 25J12<> 
J 0
(-10530 3200);
DISPLAY 0.638298 (-10530 3200);
PAINT MONO (-10530 3200);
FORCEPROP 2 LAST $XR0 12E5<> 
J 0
(-10740 3200);
DISPLAY 0.638298 (-10740 3200);
PAINT MONO (-10740 3200);
FORCEPROP 2 LAST CDS_LIB cls
J 0
(-10800 3200);
DISPLAY INVISIBLE (-10800 3200);
FORCEPROP 1 LAST CDS_LMAN_SYM_OUTLINE -50,50,50,-50
J 0
(-10800 3200);
DISPLAY 0.468085 (-10800 3200);
PAINT GREEN (-10800 3200);
DISPLAY INVISIBLE (-10800 3200);
FORCEPROP 1 LAST BODY_TYPE COMMENT
J 0
(-10790 3027);
DISPLAY 0.808511 (-10790 3027);
PAINT GREEN (-10790 3027);
DISPLAY INVISIBLE (-10790 3027);
FORCEPROP 1 LAST OFFPAGE TRUE
J 0
(-10790 3107);
DISPLAY 0.808511 (-10790 3107);
PAINT GREEN (-10790 3107);
DISPLAY INVISIBLE (-10790 3107);
FORCEPROP 2 LAST PATH I1565
J 0
(-10750 3300);
DISPLAY 1.021277 (-10750 3300);
DISPLAY INVISIBLE (-10750 3300);
FORCEADD OFFPAGE_BI..1
R 6
(-10800 2900);
FORCEPROP 2 LAST $XR1 25J7<> 
J 0
(-10530 2900);
DISPLAY 0.638298 (-10530 2900);
PAINT MONO (-10530 2900);
FORCEPROP 2 LAST $XR0 12E5<> 
J 0
(-10740 2900);
DISPLAY 0.638298 (-10740 2900);
PAINT MONO (-10740 2900);
FORCEPROP 2 LAST CDS_LIB cls
J 0
(-10800 2900);
DISPLAY INVISIBLE (-10800 2900);
FORCEPROP 1 LAST CDS_LMAN_SYM_OUTLINE -50,50,50,-50
J 0
(-10800 2900);
DISPLAY 0.468085 (-10800 2900);
PAINT GREEN (-10800 2900);
DISPLAY INVISIBLE (-10800 2900);
FORCEPROP 1 LAST BODY_TYPE COMMENT
J 0
(-10790 2727);
DISPLAY 0.808511 (-10790 2727);
PAINT GREEN (-10790 2727);
DISPLAY INVISIBLE (-10790 2727);
FORCEPROP 1 LAST OFFPAGE TRUE
J 0
(-10790 2807);
DISPLAY 0.808511 (-10790 2807);
PAINT GREEN (-10790 2807);
DISPLAY INVISIBLE (-10790 2807);
FORCEPROP 2 LAST PATH I1566
J 0
(-10750 3000);
DISPLAY 1.021277 (-10750 3000);
DISPLAY INVISIBLE (-10750 3000);
FORCEADD OFFPAGE_BI..1
R 6
(-10800 2600);
FORCEPROP 2 LAST $XR0 12E5<> 
J 0
(-10740 2600);
DISPLAY 0.638298 (-10740 2600);
PAINT MONO (-10740 2600);
FORCEPROP 2 LAST $XR1 25J7<> 
J 0
(-10530 2600);
DISPLAY 0.638298 (-10530 2600);
PAINT MONO (-10530 2600);
FORCEPROP 2 LAST CDS_LIB cls
J 0
(-10800 2600);
DISPLAY INVISIBLE (-10800 2600);
FORCEPROP 1 LAST CDS_LMAN_SYM_OUTLINE -50,50,50,-50
J 0
(-10800 2600);
DISPLAY 0.468085 (-10800 2600);
PAINT GREEN (-10800 2600);
DISPLAY INVISIBLE (-10800 2600);
FORCEPROP 1 LAST BODY_TYPE COMMENT
J 0
(-10790 2427);
DISPLAY 0.808511 (-10790 2427);
PAINT GREEN (-10790 2427);
DISPLAY INVISIBLE (-10790 2427);
FORCEPROP 1 LAST OFFPAGE TRUE
J 0
(-10790 2507);
DISPLAY 0.808511 (-10790 2507);
PAINT GREEN (-10790 2507);
DISPLAY INVISIBLE (-10790 2507);
FORCEPROP 2 LAST PATH I1567
J 0
(-10750 2700);
DISPLAY 1.021277 (-10750 2700);
DISPLAY INVISIBLE (-10750 2700);
FORCEADD OFFPAGE_BI..1
R 6
(-10800 2300);
FORCEPROP 2 LAST $XR1 25J7<> 
J 0
(-10530 2300);
DISPLAY 0.638298 (-10530 2300);
PAINT MONO (-10530 2300);
FORCEPROP 2 LAST $XR0 12E5<> 
J 0
(-10740 2300);
DISPLAY 0.638298 (-10740 2300);
PAINT MONO (-10740 2300);
FORCEPROP 2 LAST CDS_LIB cls
J 0
(-10800 2300);
DISPLAY INVISIBLE (-10800 2300);
FORCEPROP 1 LAST CDS_LMAN_SYM_OUTLINE -50,50,50,-50
J 0
(-10800 2300);
DISPLAY 0.468085 (-10800 2300);
PAINT GREEN (-10800 2300);
DISPLAY INVISIBLE (-10800 2300);
FORCEPROP 1 LAST BODY_TYPE COMMENT
J 0
(-10790 2127);
DISPLAY 0.808511 (-10790 2127);
PAINT GREEN (-10790 2127);
DISPLAY INVISIBLE (-10790 2127);
FORCEPROP 1 LAST OFFPAGE TRUE
J 0
(-10790 2207);
DISPLAY 0.808511 (-10790 2207);
PAINT GREEN (-10790 2207);
DISPLAY INVISIBLE (-10790 2207);
FORCEPROP 2 LAST PATH I1568
J 0
(-10750 2400);
DISPLAY 1.021277 (-10750 2400);
DISPLAY INVISIBLE (-10750 2400);
FORCEADD OFFPAGE_BI..1
R 6
(-10800 2000);
FORCEPROP 2 LAST $XR1 25J7<> 
J 0
(-10530 2000);
DISPLAY 0.638298 (-10530 2000);
PAINT MONO (-10530 2000);
FORCEPROP 2 LAST $XR0 12F5<> 
J 0
(-10740 2000);
DISPLAY 0.638298 (-10740 2000);
PAINT MONO (-10740 2000);
FORCEPROP 2 LAST CDS_LIB cls
J 0
(-10800 2000);
DISPLAY INVISIBLE (-10800 2000);
FORCEPROP 1 LAST CDS_LMAN_SYM_OUTLINE -50,50,50,-50
J 0
(-10800 2000);
DISPLAY 0.468085 (-10800 2000);
PAINT GREEN (-10800 2000);
DISPLAY INVISIBLE (-10800 2000);
FORCEPROP 1 LAST BODY_TYPE COMMENT
J 0
(-10790 1827);
DISPLAY 0.808511 (-10790 1827);
PAINT GREEN (-10790 1827);
DISPLAY INVISIBLE (-10790 1827);
FORCEPROP 1 LAST OFFPAGE TRUE
J 0
(-10790 1907);
DISPLAY 0.808511 (-10790 1907);
PAINT GREEN (-10790 1907);
DISPLAY INVISIBLE (-10790 1907);
FORCEPROP 2 LAST PATH I1569
J 0
(-10750 2100);
DISPLAY 1.021277 (-10750 2100);
DISPLAY INVISIBLE (-10750 2100);
FORCEADD RESISTOR..1
(-12350 2300);
FORCEPROP 1 LAST $LOCATION R325
J 2
(-12550 2300);
DISPLAY 1.212766 (-12550 2300);
PAINT GREEN (-12550 2300);
FORCEPROP 0 LAST CDS_LOCATION R325
J 0
(-12100 2400);
DISPLAY 1.021277 (-12100 2400);
DISPLAY INVISIBLE (-12100 2400);
FORCEPROP 0 LAST $SEC 1
J 0
(-12100 2400);
DISPLAY 0.680851 (-12100 2400);
PAINT MONO (-12100 2400);
DISPLAY INVISIBLE (-12100 2400);
FORCEPROP 0 LAST CDS_SEC 1
J 0
(-12100 2400);
DISPLAY 1.021277 (-12100 2400);
DISPLAY INVISIBLE (-12100 2400);
FORCEPROP 0 LASTPIN (-12450 2300) $PN 1
J 2
(-12460 2310);
DISPLAY 0.680851 (-12460 2310);
PAINT MONO (-12460 2310);
FORCEPROP 0 LASTPIN (-12200 2300) $PN 2
J 0
(-12190 2310);
DISPLAY 0.680851 (-12190 2310);
PAINT MONO (-12190 2310);
FORCEPROP 0 LAST PACKAGE 0402
J 0
(-12400 2350);
DISPLAY 0.808511 (-12400 2350);
FORCEPROP 1 LAST VALUE 10KOHM
J 0
(-12100 2300);
DISPLAY 1.212766 (-12100 2300);
PAINT GREEN (-12100 2300);
FORCEPROP 1 LAST PATH I1602
J 0
(-12547 2405);
DISPLAY 1.212766 (-12547 2405);
PAINT GREEN (-12547 2405);
DISPLAY INVISIBLE (-12547 2405);
FORCEPROP 1 LAST TOLERANCE 1%
J 0
(-12547 2555);
DISPLAY 1.212766 (-12547 2555);
PAINT GREEN (-12547 2555);
DISPLAY INVISIBLE (-12547 2555);
FORCEPROP 1 LAST CDS_LMAN_SYM_OUTLINE -50,50,100,-50
J 0
(-12350 2300);
DISPLAY 0.468085 (-12350 2300);
PAINT GREEN (-12350 2300);
DISPLAY INVISIBLE (-12350 2300);
FORCEPROP 2 LAST CDS_LIB passive
J 0
(-12350 2300);
DISPLAY INVISIBLE (-12350 2300);
FORCEPROP 1 LAST CLS_PN G155-11002-01
J 0
(-12486 2500);
DISPLAY 1.212766 (-12486 2500);
PAINT GREEN (-12486 2500);
DISPLAY INVISIBLE (-12486 2500);
FORCEADD RESISTOR..1
(-12350 2000);
FORCEPROP 1 LAST $LOCATION R327
J 2
(-12550 2000);
DISPLAY 1.212766 (-12550 2000);
PAINT GREEN (-12550 2000);
FORCEPROP 0 LAST CDS_LOCATION R327
J 0
(-12100 2100);
DISPLAY 1.021277 (-12100 2100);
DISPLAY INVISIBLE (-12100 2100);
FORCEPROP 0 LAST $SEC 1
J 0
(-12100 2100);
DISPLAY 0.680851 (-12100 2100);
PAINT MONO (-12100 2100);
DISPLAY INVISIBLE (-12100 2100);
FORCEPROP 0 LAST CDS_SEC 1
J 0
(-12100 2100);
DISPLAY 1.021277 (-12100 2100);
DISPLAY INVISIBLE (-12100 2100);
FORCEPROP 0 LASTPIN (-12450 2000) $PN 1
J 2
(-12460 2010);
DISPLAY 0.680851 (-12460 2010);
PAINT MONO (-12460 2010);
FORCEPROP 0 LASTPIN (-12200 2000) $PN 2
J 0
(-12190 2010);
DISPLAY 0.680851 (-12190 2010);
PAINT MONO (-12190 2010);
FORCEPROP 1 LAST VALUE 10KOHM
J 0
(-12100 2000);
DISPLAY 1.212766 (-12100 2000);
PAINT GREEN (-12100 2000);
FORCEPROP 0 LAST PACKAGE 0402
J 0
(-12400 2050);
DISPLAY 0.808511 (-12400 2050);
FORCEPROP 1 LAST TOLERANCE 1%
J 0
(-12547 2255);
DISPLAY 1.212766 (-12547 2255);
PAINT GREEN (-12547 2255);
DISPLAY INVISIBLE (-12547 2255);
FORCEPROP 1 LAST CDS_LMAN_SYM_OUTLINE -50,50,100,-50
J 0
(-12350 2000);
DISPLAY 0.468085 (-12350 2000);
PAINT GREEN (-12350 2000);
DISPLAY INVISIBLE (-12350 2000);
FORCEPROP 2 LAST CDS_LIB passive
J 0
(-12350 2000);
DISPLAY INVISIBLE (-12350 2000);
FORCEPROP 1 LAST CLS_PN G155-11002-01
J 0
(-12486 2200);
DISPLAY 1.212766 (-12486 2200);
PAINT GREEN (-12486 2200);
DISPLAY INVISIBLE (-12486 2200);
FORCEPROP 1 LAST PATH I1603
J 0
(-12547 2105);
DISPLAY 1.212766 (-12547 2105);
PAINT GREEN (-12547 2105);
DISPLAY INVISIBLE (-12547 2105);
FORCEADD RESISTOR..1
(-12350 2600);
FORCEPROP 1 LAST $LOCATION R308
J 2
(-12550 2600);
DISPLAY 1.212766 (-12550 2600);
PAINT GREEN (-12550 2600);
FORCEPROP 0 LAST CDS_LOCATION R308
J 0
(-12100 2700);
DISPLAY 1.021277 (-12100 2700);
DISPLAY INVISIBLE (-12100 2700);
FORCEPROP 0 LAST $SEC 1
J 0
(-12100 2700);
DISPLAY 0.680851 (-12100 2700);
PAINT MONO (-12100 2700);
DISPLAY INVISIBLE (-12100 2700);
FORCEPROP 0 LAST CDS_SEC 1
J 0
(-12100 2700);
DISPLAY 1.021277 (-12100 2700);
DISPLAY INVISIBLE (-12100 2700);
FORCEPROP 0 LASTPIN (-12450 2600) $PN 1
J 2
(-12460 2610);
DISPLAY 0.680851 (-12460 2610);
PAINT MONO (-12460 2610);
FORCEPROP 0 LASTPIN (-12200 2600) $PN 2
J 0
(-12190 2610);
DISPLAY 0.680851 (-12190 2610);
PAINT MONO (-12190 2610);
FORCEPROP 1 LAST VALUE 10KOHM
J 0
(-12100 2600);
DISPLAY 1.212766 (-12100 2600);
PAINT GREEN (-12100 2600);
FORCEPROP 0 LAST PACKAGE 0402
J 0
(-12400 2650);
DISPLAY 0.808511 (-12400 2650);
FORCEPROP 1 LAST TOLERANCE 1%
J 0
(-12547 2855);
DISPLAY 1.212766 (-12547 2855);
PAINT GREEN (-12547 2855);
DISPLAY INVISIBLE (-12547 2855);
FORCEPROP 1 LAST CDS_LMAN_SYM_OUTLINE -50,50,100,-50
J 0
(-12350 2600);
DISPLAY 0.468085 (-12350 2600);
PAINT GREEN (-12350 2600);
DISPLAY INVISIBLE (-12350 2600);
FORCEPROP 2 LAST CDS_LIB passive
J 0
(-12350 2600);
DISPLAY INVISIBLE (-12350 2600);
FORCEPROP 1 LAST CLS_PN G155-11002-01
J 0
(-12486 2800);
DISPLAY 1.212766 (-12486 2800);
PAINT GREEN (-12486 2800);
DISPLAY INVISIBLE (-12486 2800);
FORCEPROP 1 LAST PATH I1604
J 0
(-12547 2705);
DISPLAY 1.212766 (-12547 2705);
PAINT GREEN (-12547 2705);
DISPLAY INVISIBLE (-12547 2705);
FORCEADD RESISTOR..1
(-12350 2900);
FORCEPROP 1 LAST $LOCATION R292
J 2
(-12550 2900);
DISPLAY 1.212766 (-12550 2900);
PAINT GREEN (-12550 2900);
FORCEPROP 0 LAST CDS_LOCATION R292
J 0
(-12100 3000);
DISPLAY 1.021277 (-12100 3000);
DISPLAY INVISIBLE (-12100 3000);
FORCEPROP 0 LAST $SEC 1
J 0
(-12100 3000);
DISPLAY 0.680851 (-12100 3000);
PAINT MONO (-12100 3000);
DISPLAY INVISIBLE (-12100 3000);
FORCEPROP 0 LAST CDS_SEC 1
J 0
(-12100 3000);
DISPLAY 1.021277 (-12100 3000);
DISPLAY INVISIBLE (-12100 3000);
FORCEPROP 0 LASTPIN (-12450 2900) $PN 1
J 2
(-12460 2910);
DISPLAY 0.680851 (-12460 2910);
PAINT MONO (-12460 2910);
FORCEPROP 0 LASTPIN (-12200 2900) $PN 2
J 0
(-12190 2910);
DISPLAY 0.680851 (-12190 2910);
PAINT MONO (-12190 2910);
FORCEPROP 1 LAST VALUE 10KOHM
J 0
(-12100 2900);
DISPLAY 1.212766 (-12100 2900);
PAINT GREEN (-12100 2900);
FORCEPROP 0 LAST PACKAGE 0402
J 0
(-12400 2950);
DISPLAY 0.808511 (-12400 2950);
FORCEPROP 1 LAST TOLERANCE 1%
J 0
(-12547 3155);
DISPLAY 1.212766 (-12547 3155);
PAINT GREEN (-12547 3155);
DISPLAY INVISIBLE (-12547 3155);
FORCEPROP 1 LAST CDS_LMAN_SYM_OUTLINE -50,50,100,-50
J 0
(-12350 2900);
DISPLAY 0.468085 (-12350 2900);
PAINT GREEN (-12350 2900);
DISPLAY INVISIBLE (-12350 2900);
FORCEPROP 2 LAST CDS_LIB passive
J 0
(-12350 2900);
DISPLAY INVISIBLE (-12350 2900);
FORCEPROP 1 LAST CLS_PN G155-11002-01
J 0
(-12486 3100);
DISPLAY 1.212766 (-12486 3100);
PAINT GREEN (-12486 3100);
DISPLAY INVISIBLE (-12486 3100);
FORCEPROP 1 LAST PATH I1605
J 0
(-12547 3005);
DISPLAY 1.212766 (-12547 3005);
PAINT GREEN (-12547 3005);
DISPLAY INVISIBLE (-12547 3005);
FORCEADD RESISTOR..1
(-12350 3200);
FORCEPROP 1 LAST $LOCATION R285
J 2
(-12550 3200);
DISPLAY 1.212766 (-12550 3200);
PAINT GREEN (-12550 3200);
FORCEPROP 0 LAST CDS_LOCATION R285
J 0
(-12100 3300);
DISPLAY 1.021277 (-12100 3300);
DISPLAY INVISIBLE (-12100 3300);
FORCEPROP 0 LAST $SEC 1
J 0
(-12100 3300);
DISPLAY 0.680851 (-12100 3300);
PAINT MONO (-12100 3300);
DISPLAY INVISIBLE (-12100 3300);
FORCEPROP 0 LAST CDS_SEC 1
J 0
(-12100 3300);
DISPLAY 1.021277 (-12100 3300);
DISPLAY INVISIBLE (-12100 3300);
FORCEPROP 0 LASTPIN (-12450 3200) $PN 1
J 2
(-12460 3210);
DISPLAY 0.680851 (-12460 3210);
PAINT MONO (-12460 3210);
FORCEPROP 0 LASTPIN (-12200 3200) $PN 2
J 0
(-12190 3210);
DISPLAY 0.680851 (-12190 3210);
PAINT MONO (-12190 3210);
FORCEPROP 0 LAST PACKAGE 0402
J 0
(-12400 3250);
DISPLAY 0.808511 (-12400 3250);
FORCEPROP 1 LAST VALUE 10KOHM
J 0
(-12100 3200);
DISPLAY 1.212766 (-12100 3200);
PAINT GREEN (-12100 3200);
FORCEPROP 1 LAST TOLERANCE 1%
J 0
(-12547 3455);
DISPLAY 1.212766 (-12547 3455);
PAINT GREEN (-12547 3455);
DISPLAY INVISIBLE (-12547 3455);
FORCEPROP 1 LAST CDS_LMAN_SYM_OUTLINE -50,50,100,-50
J 0
(-12350 3200);
DISPLAY 0.468085 (-12350 3200);
PAINT GREEN (-12350 3200);
DISPLAY INVISIBLE (-12350 3200);
FORCEPROP 2 LAST CDS_LIB passive
J 0
(-12350 3200);
DISPLAY INVISIBLE (-12350 3200);
FORCEPROP 1 LAST CLS_PN G155-11002-01
J 0
(-12486 3400);
DISPLAY 1.212766 (-12486 3400);
PAINT GREEN (-12486 3400);
DISPLAY INVISIBLE (-12486 3400);
FORCEPROP 1 LAST PATH I1606
J 0
(-12547 3305);
DISPLAY 1.212766 (-12547 3305);
PAINT GREEN (-12547 3305);
DISPLAY INVISIBLE (-12547 3305);
FORCEADD RESISTOR..1
(-12350 3800);
FORCEPROP 1 LAST $LOCATION R172
J 2
(-12550 3800);
DISPLAY 1.212766 (-12550 3800);
PAINT GREEN (-12550 3800);
FORCEPROP 0 LAST CDS_LOCATION R172
J 0
(-12100 3900);
DISPLAY 1.021277 (-12100 3900);
DISPLAY INVISIBLE (-12100 3900);
FORCEPROP 0 LAST $SEC 1
J 0
(-12100 3900);
DISPLAY 0.680851 (-12100 3900);
PAINT MONO (-12100 3900);
DISPLAY INVISIBLE (-12100 3900);
FORCEPROP 0 LAST CDS_SEC 1
J 0
(-12100 3900);
DISPLAY 1.021277 (-12100 3900);
DISPLAY INVISIBLE (-12100 3900);
FORCEPROP 0 LASTPIN (-12450 3800) $PN 1
J 2
(-12460 3810);
DISPLAY 0.680851 (-12460 3810);
PAINT MONO (-12460 3810);
FORCEPROP 0 LASTPIN (-12200 3800) $PN 2
J 0
(-12190 3810);
DISPLAY 0.680851 (-12190 3810);
PAINT MONO (-12190 3810);
FORCEPROP 0 LAST PACKAGE 0402
J 0
(-12400 3850);
DISPLAY 0.808511 (-12400 3850);
FORCEPROP 1 LAST VALUE 10KOHM
J 0
(-12100 3800);
DISPLAY 1.212766 (-12100 3800);
PAINT GREEN (-12100 3800);
FORCEPROP 1 LAST TOLERANCE 1%
J 0
(-12547 4055);
DISPLAY 1.212766 (-12547 4055);
PAINT GREEN (-12547 4055);
DISPLAY INVISIBLE (-12547 4055);
FORCEPROP 1 LAST CDS_LMAN_SYM_OUTLINE -50,50,100,-50
J 0
(-12350 3800);
DISPLAY 0.468085 (-12350 3800);
PAINT GREEN (-12350 3800);
DISPLAY INVISIBLE (-12350 3800);
FORCEPROP 2 LAST CDS_LIB passive
J 0
(-12350 3800);
DISPLAY INVISIBLE (-12350 3800);
FORCEPROP 1 LAST CLS_PN G155-11002-01
J 0
(-12486 4000);
DISPLAY 1.212766 (-12486 4000);
PAINT GREEN (-12486 4000);
DISPLAY INVISIBLE (-12486 4000);
FORCEPROP 1 LAST PATH I1607
J 0
(-12547 3905);
DISPLAY 1.212766 (-12547 3905);
PAINT GREEN (-12547 3905);
DISPLAY INVISIBLE (-12547 3905);
FORCEADD RESISTOR..1
(-12350 4100);
FORCEPROP 1 LAST $LOCATION R170
J 2
(-12550 4100);
DISPLAY 1.212766 (-12550 4100);
PAINT GREEN (-12550 4100);
FORCEPROP 0 LAST CDS_LOCATION R170
J 0
(-12100 4200);
DISPLAY 1.021277 (-12100 4200);
DISPLAY INVISIBLE (-12100 4200);
FORCEPROP 0 LAST $SEC 1
J 0
(-12100 4200);
DISPLAY 0.680851 (-12100 4200);
PAINT MONO (-12100 4200);
DISPLAY INVISIBLE (-12100 4200);
FORCEPROP 0 LAST CDS_SEC 1
J 0
(-12100 4200);
DISPLAY 1.021277 (-12100 4200);
DISPLAY INVISIBLE (-12100 4200);
FORCEPROP 0 LASTPIN (-12450 4100) $PN 1
J 2
(-12460 4110);
DISPLAY 0.680851 (-12460 4110);
PAINT MONO (-12460 4110);
FORCEPROP 0 LASTPIN (-12200 4100) $PN 2
J 0
(-12190 4110);
DISPLAY 0.680851 (-12190 4110);
PAINT MONO (-12190 4110);
FORCEPROP 1 LAST VALUE 10KOHM
J 0
(-12100 4100);
DISPLAY 1.212766 (-12100 4100);
PAINT GREEN (-12100 4100);
FORCEPROP 0 LAST PACKAGE 0402
J 0
(-12400 4150);
DISPLAY 0.808511 (-12400 4150);
FORCEPROP 1 LAST TOLERANCE 1%
J 0
(-12547 4355);
DISPLAY 1.212766 (-12547 4355);
PAINT GREEN (-12547 4355);
DISPLAY INVISIBLE (-12547 4355);
FORCEPROP 1 LAST CDS_LMAN_SYM_OUTLINE -50,50,100,-50
J 0
(-12350 4100);
DISPLAY 0.468085 (-12350 4100);
PAINT GREEN (-12350 4100);
DISPLAY INVISIBLE (-12350 4100);
FORCEPROP 2 LAST CDS_LIB passive
J 0
(-12350 4100);
DISPLAY INVISIBLE (-12350 4100);
FORCEPROP 1 LAST CLS_PN G155-11002-01
J 0
(-12486 4300);
DISPLAY 1.212766 (-12486 4300);
PAINT GREEN (-12486 4300);
DISPLAY INVISIBLE (-12486 4300);
FORCEPROP 1 LAST PATH I1608
J 0
(-12547 4205);
DISPLAY 1.212766 (-12547 4205);
PAINT GREEN (-12547 4205);
DISPLAY INVISIBLE (-12547 4205);
FORCEADD RESISTOR..1
(-12350 3500);
FORCEPROP 1 LAST $LOCATION R283
J 2
(-12550 3500);
DISPLAY 1.212766 (-12550 3500);
PAINT GREEN (-12550 3500);
FORCEPROP 0 LAST CDS_LOCATION R283
J 0
(-12100 3600);
DISPLAY 1.021277 (-12100 3600);
DISPLAY INVISIBLE (-12100 3600);
FORCEPROP 0 LAST $SEC 1
J 0
(-12100 3600);
DISPLAY 0.680851 (-12100 3600);
PAINT MONO (-12100 3600);
DISPLAY INVISIBLE (-12100 3600);
FORCEPROP 0 LAST CDS_SEC 1
J 0
(-12100 3600);
DISPLAY 1.021277 (-12100 3600);
DISPLAY INVISIBLE (-12100 3600);
FORCEPROP 0 LASTPIN (-12450 3500) $PN 1
J 2
(-12460 3510);
DISPLAY 0.680851 (-12460 3510);
PAINT MONO (-12460 3510);
FORCEPROP 0 LASTPIN (-12200 3500) $PN 2
J 0
(-12190 3510);
DISPLAY 0.680851 (-12190 3510);
PAINT MONO (-12190 3510);
FORCEPROP 1 LAST VALUE 10KOHM
J 0
(-12100 3500);
DISPLAY 1.212766 (-12100 3500);
PAINT GREEN (-12100 3500);
FORCEPROP 0 LAST PACKAGE 0402
J 0
(-12400 3550);
DISPLAY 0.808511 (-12400 3550);
FORCEPROP 1 LAST TOLERANCE 1%
J 0
(-12547 3755);
DISPLAY 1.212766 (-12547 3755);
PAINT GREEN (-12547 3755);
DISPLAY INVISIBLE (-12547 3755);
FORCEPROP 1 LAST CDS_LMAN_SYM_OUTLINE -50,50,100,-50
J 0
(-12350 3500);
DISPLAY 0.468085 (-12350 3500);
PAINT GREEN (-12350 3500);
DISPLAY INVISIBLE (-12350 3500);
FORCEPROP 2 LAST CDS_LIB passive
J 0
(-12350 3500);
DISPLAY INVISIBLE (-12350 3500);
FORCEPROP 1 LAST CLS_PN G155-11002-01
J 0
(-12486 3700);
DISPLAY 1.212766 (-12486 3700);
PAINT GREEN (-12486 3700);
DISPLAY INVISIBLE (-12486 3700);
FORCEPROP 1 LAST PATH I1609
J 0
(-12547 3605);
DISPLAY 1.212766 (-12547 3605);
PAINT GREEN (-12547 3605);
DISPLAY INVISIBLE (-12547 3605);
FORCEADD TP_PIONT..1
(-3300 7800);
FORCEPROP 1 LAST $LOCATION TP3
J 0
(-3200 7800);
DISPLAY 0.808511 (-3200 7800);
PAINT GREEN (-3200 7800);
FORCEPROP 0 LAST CDS_LOCATION TP3
J 0
(-3200 7850);
DISPLAY 1.021277 (-3200 7850);
DISPLAY INVISIBLE (-3200 7850);
FORCEPROP 0 LAST $SEC 1
J 0
(-3200 7850);
DISPLAY 0.680851 (-3200 7850);
PAINT MONO (-3200 7850);
DISPLAY INVISIBLE (-3200 7850);
FORCEPROP 0 LAST CDS_SEC 1
J 0
(-3200 7850);
DISPLAY 1.021277 (-3200 7850);
DISPLAY INVISIBLE (-3200 7850);
FORCEPROP 0 LASTPIN (-3400 7800) $PN 1
J 2
(-3410 7810);
DISPLAY 0.680851 (-3410 7810);
PAINT MONO (-3410 7810);
FORCEPROP 1 LAST BOM_IGNORE TRUE
J 0
(-3424 7900);
DISPLAY 0.000000 (-3424 7900);
PAINT GREEN (-3424 7900);
DISPLAY INVISIBLE (-3424 7900);
FORCEPROP 1 LAST JEDEC_TYPE TP010CT020B030_PTH
J 0
(-3424 7900);
DISPLAY 0.000000 (-3424 7900);
PAINT GREEN (-3424 7900);
DISPLAY INVISIBLE (-3424 7900);
FORCEPROP 1 LAST CDS_LMAN_SYM_OUTLINE -50,50,50,-50
J 0
(-3300 7800);
DISPLAY 0.468085 (-3300 7800);
PAINT GREEN (-3300 7800);
DISPLAY INVISIBLE (-3300 7800);
FORCEPROP 1 LAST PATH I1610
J 0
(-3220 7913);
DISPLAY 0.808511 (-3220 7913);
PAINT GREEN (-3220 7913);
DISPLAY INVISIBLE (-3220 7913);
FORCEPROP 2 LAST CDS_LIB cls
J 0
(-3300 7800);
DISPLAY INVISIBLE (-3300 7800);
FORCEADD VCC..1
(-4300 7950);
FORCEPROP 3 LASTPIN (-4250 7900) SIG_NAME XP3R3V_FT4232\g
J 0
(-4240 7910);
DISPLAY 0.659574 (-4240 7910);
PAINT MONO (-4240 7910);
DISPLAY INVISIBLE (-4240 7910);
FORCEPROP 0 LAST VOLTAGE 3.3V
J 0
(-4550 8100);
DISPLAY 1.021277 (-4550 8100);
DISPLAY BOTH (-4550 8100);
FORCEPROP 1 LAST HDL_POWER XP3R3V_FT4232
J 1
(-4245 8005);
DISPLAY 1.021277 (-4245 8005);
PAINT GREEN (-4245 8005);
FORCEPROP 1 LAST CDS_LMAN_SYM_OUTLINE -250,250,250,-250
J 0
(-4300 7950);
DISPLAY 0.468085 (-4300 7950);
PAINT GREEN (-4300 7950);
DISPLAY INVISIBLE (-4300 7950);
FORCEPROP 2 LAST CDS_LIB cls
J 0
(-4300 7950);
DISPLAY INVISIBLE (-4300 7950);
FORCEPROP 1 LAST PATH I1611
J 0
(-4265 8040);
DISPLAY 0.808511 (-4265 8040);
PAINT GREEN (-4265 8040);
DISPLAY INVISIBLE (-4265 8040);
FORCEPROP 1 LAST BODY_TYPE PLUMBING
J 0
(-4345 7907);
DISPLAY 0.340426 (-4345 7907);
PAINT GREEN (-4345 7907);
DISPLAY INVISIBLE (-4345 7907);
FORCEADD TP_PIONT..1
(-3300 7350);
FORCEPROP 1 LAST $LOCATION TP4
J 0
(-3200 7350);
DISPLAY 0.808511 (-3200 7350);
PAINT GREEN (-3200 7350);
FORCEPROP 0 LAST CDS_LOCATION TP4
J 0
(-3200 7400);
DISPLAY 1.021277 (-3200 7400);
DISPLAY INVISIBLE (-3200 7400);
FORCEPROP 0 LAST $SEC 1
J 0
(-3200 7400);
DISPLAY 0.680851 (-3200 7400);
PAINT MONO (-3200 7400);
DISPLAY INVISIBLE (-3200 7400);
FORCEPROP 0 LAST CDS_SEC 1
J 0
(-3200 7400);
DISPLAY 1.021277 (-3200 7400);
DISPLAY INVISIBLE (-3200 7400);
FORCEPROP 0 LASTPIN (-3400 7350) $PN 1
J 2
(-3410 7360);
DISPLAY 0.680851 (-3410 7360);
PAINT MONO (-3410 7360);
FORCEPROP 1 LAST BOM_IGNORE TRUE
J 0
(-3424 7450);
DISPLAY 0.000000 (-3424 7450);
PAINT GREEN (-3424 7450);
DISPLAY INVISIBLE (-3424 7450);
FORCEPROP 1 LAST JEDEC_TYPE TP010CT020B030_PTH
J 0
(-3424 7450);
DISPLAY 0.000000 (-3424 7450);
PAINT GREEN (-3424 7450);
DISPLAY INVISIBLE (-3424 7450);
FORCEPROP 1 LAST CDS_LMAN_SYM_OUTLINE -50,50,50,-50
J 0
(-3300 7350);
DISPLAY 0.468085 (-3300 7350);
PAINT GREEN (-3300 7350);
DISPLAY INVISIBLE (-3300 7350);
FORCEPROP 2 LAST CDS_LIB cls
J 0
(-3300 7350);
DISPLAY INVISIBLE (-3300 7350);
FORCEPROP 1 LAST PATH I1612
J 0
(-3220 7463);
DISPLAY 0.808511 (-3220 7463);
PAINT GREEN (-3220 7463);
DISPLAY INVISIBLE (-3220 7463);
FORCEADD VCC..1
(-4300 7500);
FORCEPROP 3 LASTPIN (-4250 7450) SIG_NAME XP5R0V_FT4232\g
J 0
(-4240 7460);
DISPLAY 0.659574 (-4240 7460);
PAINT MONO (-4240 7460);
DISPLAY INVISIBLE (-4240 7460);
FORCEPROP 0 LAST VOLTAGE 5V
J 1
(-4250 7600);
DISPLAY 1.021277 (-4250 7600);
DISPLAY BOTH (-4250 7600);
FORCEPROP 1 LAST HDL_POWER XP5R0V_FT4232
J 1
(-4250 7550);
DISPLAY 0.808511 (-4250 7550);
PAINT GREEN (-4250 7550);
FORCEPROP 1 LAST BODY_TYPE PLUMBING
J 0
(-4345 7457);
DISPLAY 0.340426 (-4345 7457);
PAINT GREEN (-4345 7457);
DISPLAY INVISIBLE (-4345 7457);
FORCEPROP 1 LAST CDS_LMAN_SYM_OUTLINE -250,250,250,-250
J 0
(-4300 7500);
DISPLAY 0.468085 (-4300 7500);
PAINT GREEN (-4300 7500);
DISPLAY INVISIBLE (-4300 7500);
FORCEPROP 2 LAST CDS_LIB cls
J 0
(-4300 7500);
DISPLAY INVISIBLE (-4300 7500);
FORCEPROP 1 LAST PATH I1613
J 0
(-4265 7590);
DISPLAY 0.808511 (-4265 7590);
PAINT GREEN (-4265 7590);
DISPLAY INVISIBLE (-4265 7590);
FORCEADD CONN_HDR_2X6_F_S_SMT..1
R 4
(-5900 2850);
FORCEPROP 1 LAST LOCATION J5
J 0
(-5500 3700);
DISPLAY 1.212766 (-5500 3700);
PAINT GREEN (-5500 3700);
FORCEPROP 0 LAST $SEC 1
R 2
J 2
(-6200 2700);
DISPLAY 0.680851 (-6200 2700);
PAINT MONO (-6200 2700);
DISPLAY INVISIBLE (-6200 2700);
FORCEPROP 0 LAST CDS_SEC 1
R 2
J 2
(-6200 2700);
DISPLAY 1.021277 (-6200 2700);
DISPLAY INVISIBLE (-6200 2700);
FORCEPROP 0 LASTPIN (-6400 2950) $PN 1
J 2
(-6360 2960);
DISPLAY 0.680851 (-6360 2960);
PAINT MONO (-6360 2960);
FORCEPROP 0 LASTPIN (-5800 2950) $PN 2
J 0
(-5860 2960);
DISPLAY 0.680851 (-5860 2960);
PAINT MONO (-5860 2960);
FORCEPROP 0 LASTPIN (-6400 3050) $PN 3
J 2
(-6360 3060);
DISPLAY 0.680851 (-6360 3060);
PAINT MONO (-6360 3060);
FORCEPROP 0 LASTPIN (-5800 3050) $PN 4
J 0
(-5860 3060);
DISPLAY 0.680851 (-5860 3060);
PAINT MONO (-5860 3060);
FORCEPROP 0 LASTPIN (-6400 3150) $PN 5
J 2
(-6360 3160);
DISPLAY 0.680851 (-6360 3160);
PAINT MONO (-6360 3160);
FORCEPROP 0 LASTPIN (-5800 3150) $PN 6
J 0
(-5860 3160);
DISPLAY 0.680851 (-5860 3160);
PAINT MONO (-5860 3160);
FORCEPROP 0 LASTPIN (-6400 3250) $PN 7
J 2
(-6360 3260);
DISPLAY 0.680851 (-6360 3260);
PAINT MONO (-6360 3260);
FORCEPROP 0 LASTPIN (-5800 3250) $PN 8
J 0
(-5860 3260);
DISPLAY 0.680851 (-5860 3260);
PAINT MONO (-5860 3260);
FORCEPROP 0 LASTPIN (-6400 3350) $PN 9
J 2
(-6360 3360);
DISPLAY 0.680851 (-6360 3360);
PAINT MONO (-6360 3360);
FORCEPROP 0 LASTPIN (-5800 3350) $PN 10
J 0
(-5860 3360);
DISPLAY 0.680851 (-5860 3360);
PAINT MONO (-5860 3360);
FORCEPROP 0 LASTPIN (-6400 3450) $PN 11
J 2
(-6360 3460);
DISPLAY 0.680851 (-6360 3460);
PAINT MONO (-6360 3460);
FORCEPROP 0 LASTPIN (-5800 3450) $PN 12
J 0
(-5860 3460);
DISPLAY 0.680851 (-5860 3460);
PAINT MONO (-5860 3460);
FORCEPROP 1 LAST CLS_PN G200-13133-01
J 0
(-5500 3600);
DISPLAY 1.212766 (-5500 3600);
PAINT GREEN (-5500 3600);
FORCEPROP 1 LAST VALUE SMH-106-02-L-D-TR
J 0
(-5500 3500);
DISPLAY 1.212766 (-5500 3500);
PAINT GREEN (-5500 3500);
FORCEPROP 2 LASTPIN (-6400 3150) SIG_NAME UN$16$CONNHDR2X6FSSMT$I1614$5
J 0
(-6390 3160);
DISPLAY 0.659574 (-6390 3160);
PAINT MONO (-6390 3160);
DISPLAY INVISIBLE (-6390 3160);
FORCEPROP 2 LASTPIN (-5800 3150) SIG_NAME UN$16$CONNHDR2X6FSSMT$I1614$6
J 0
(-5790 3160);
DISPLAY 0.659574 (-5790 3160);
PAINT MONO (-5790 3160);
DISPLAY INVISIBLE (-5790 3160);
FORCEPROP 2 LASTPIN (-6400 3250) SIG_NAME UN$16$CONNHDR2X6FSSMT$I1614$7
R 2
J 2
(-6390 3240);
DISPLAY 0.659574 (-6390 3240);
PAINT MONO (-6390 3240);
DISPLAY INVISIBLE (-6390 3240);
FORCEPROP 2 LASTPIN (-6400 3050) SIG_NAME UN$16$CONNHDR2X6FSSMT$I1614$3
R 2
J 2
(-6390 3040);
DISPLAY 0.659574 (-6390 3040);
PAINT MONO (-6390 3040);
DISPLAY INVISIBLE (-6390 3040);
FORCEPROP 2 LASTPIN (-6400 2950) SIG_NAME UN$16$CONNHDR2X6FSSMT$I1614$1
R 2
J 2
(-6390 2940);
DISPLAY 0.659574 (-6390 2940);
PAINT MONO (-6390 2940);
DISPLAY INVISIBLE (-6390 2940);
FORCEPROP 2 LASTPIN (-5800 3250) SIG_NAME UN$16$CONNHDR2X6FSSMT$I1614$8
R 2
J 2
(-5790 3240);
DISPLAY 0.659574 (-5790 3240);
PAINT MONO (-5790 3240);
DISPLAY INVISIBLE (-5790 3240);
FORCEPROP 2 LASTPIN (-5800 2950) SIG_NAME UN$16$CONNHDR2X6FSSMT$I1614$2
R 2
J 2
(-5790 2940);
DISPLAY 0.659574 (-5790 2940);
PAINT MONO (-5790 2940);
DISPLAY INVISIBLE (-5790 2940);
FORCEPROP 2 LASTPIN (-5800 3050) SIG_NAME UN$16$CONNHDR2X6FSSMT$I1614$4
R 2
J 2
(-5790 3040);
DISPLAY 0.659574 (-5790 3040);
PAINT MONO (-5790 3040);
DISPLAY INVISIBLE (-5790 3040);
FORCEPROP 1 LAST CDS_LMAN_SYM_OUTLINE 0,0,400,-700
R 2
J 0
(-5900 2850);
DISPLAY 0.468085 (-5900 2850);
PAINT GREEN (-5900 2850);
DISPLAY INVISIBLE (-5900 2850);
FORCEPROP 1 LAST PATH I1614
R 2
J 0
(-5950 2800);
DISPLAY 1.212766 (-5950 2800);
PAINT GREEN (-5950 2800);
DISPLAY INVISIBLE (-5950 2800);
FORCEPROP 2 LAST CDS_LIB connector
R 2
J 0
(-5900 2850);
DISPLAY INVISIBLE (-5900 2850);
FORCEADD TP_PIONT..1
R 2
(-10950 8550);
FORCEPROP 1 LAST $LOCATION TP20
J 2
(-11100 8550);
DISPLAY 0.808511 (-11100 8550);
PAINT GREEN (-11100 8550);
FORCEPROP 0 LAST CDS_LOCATION TP20
J 0
(-11100 8600);
DISPLAY 1.021277 (-11100 8600);
DISPLAY INVISIBLE (-11100 8600);
FORCEPROP 0 LAST $SEC 1
J 0
(-11100 8600);
DISPLAY 0.680851 (-11100 8600);
PAINT MONO (-11100 8600);
DISPLAY INVISIBLE (-11100 8600);
FORCEPROP 0 LAST CDS_SEC 1
J 0
(-11100 8600);
DISPLAY 1.021277 (-11100 8600);
DISPLAY INVISIBLE (-11100 8600);
FORCEPROP 0 LASTPIN (-10850 8550) $PN 1
J 0
(-10840 8560);
DISPLAY 0.680851 (-10840 8560);
PAINT MONO (-10840 8560);
FORCEPROP 1 LAST BOM_IGNORE TRUE
J 2
(-10826 8650);
DISPLAY 0.000000 (-10826 8650);
PAINT GREEN (-10826 8650);
DISPLAY INVISIBLE (-10826 8650);
FORCEPROP 1 LAST JEDEC_TYPE TP010CT020B030_PTH
J 2
(-10826 8650);
DISPLAY 0.000000 (-10826 8650);
PAINT GREEN (-10826 8650);
DISPLAY INVISIBLE (-10826 8650);
FORCEPROP 1 LAST PATH I1615
J 2
(-11030 8663);
DISPLAY 0.808511 (-11030 8663);
PAINT GREEN (-11030 8663);
DISPLAY INVISIBLE (-11030 8663);
FORCEPROP 2 LAST CDS_LIB cls
J 0
(-10950 8550);
DISPLAY INVISIBLE (-10950 8550);
FORCEPROP 1 LAST CDS_LMAN_SYM_OUTLINE -50,50,50,-50
J 2
(-10950 8550);
DISPLAY 0.468085 (-10950 8550);
PAINT GREEN (-10950 8550);
DISPLAY INVISIBLE (-10950 8550);
FORCEADD OFFPAGE_BI..1
R 6
(-9600 8650);
FORCEPROP 2 LAST $XR0 16J12< 
J 0
(-9540 8650);
DISPLAY 0.638298 (-9540 8650);
PAINT MONO (-9540 8650);
FORCEPROP 1 LAST OFFPAGE TRUE
J 0
(-9590 8557);
DISPLAY 0.808511 (-9590 8557);
PAINT GREEN (-9590 8557);
DISPLAY INVISIBLE (-9590 8557);
FORCEPROP 1 LAST BODY_TYPE COMMENT
J 0
(-9590 8477);
DISPLAY 0.808511 (-9590 8477);
PAINT GREEN (-9590 8477);
DISPLAY INVISIBLE (-9590 8477);
FORCEPROP 2 LAST PATH I1616
J 0
(-9550 8750);
DISPLAY 1.021277 (-9550 8750);
DISPLAY INVISIBLE (-9550 8750);
FORCEPROP 2 LAST CDS_LIB cls
J 0
(-9600 8650);
DISPLAY INVISIBLE (-9600 8650);
FORCEPROP 1 LAST CDS_LMAN_SYM_OUTLINE -50,50,50,-50
J 0
(-9600 8650);
DISPLAY 0.468085 (-9600 8650);
PAINT GREEN (-9600 8650);
DISPLAY INVISIBLE (-9600 8650);
FORCEADD OFFPAGE_BI..1
R 6
(-9600 9500);
FORCEPROP 2 LAST $XR0 24E5> 
J 0
(-9540 9500);
DISPLAY 0.638298 (-9540 9500);
PAINT MONO (-9540 9500);
FORCEPROP 2 LAST $XR1 24K1< 
J 0
(-9360 9500);
DISPLAY 0.638298 (-9360 9500);
PAINT MONO (-9360 9500);
FORCEPROP 1 LAST BODY_TYPE COMMENT
J 0
(-9590 9327);
DISPLAY 0.808511 (-9590 9327);
PAINT GREEN (-9590 9327);
DISPLAY INVISIBLE (-9590 9327);
FORCEPROP 1 LAST OFFPAGE TRUE
J 0
(-9590 9407);
DISPLAY 0.808511 (-9590 9407);
PAINT GREEN (-9590 9407);
DISPLAY INVISIBLE (-9590 9407);
FORCEPROP 2 LAST PATH I1617
J 0
(-9550 9600);
DISPLAY 1.021277 (-9550 9600);
DISPLAY INVISIBLE (-9550 9600);
FORCEPROP 1 LAST CDS_LMAN_SYM_OUTLINE -50,50,50,-50
J 0
(-9600 9500);
DISPLAY 0.468085 (-9600 9500);
PAINT GREEN (-9600 9500);
DISPLAY INVISIBLE (-9600 9500);
FORCEPROP 2 LAST CDS_LIB cls
J 0
(-9600 9500);
DISPLAY INVISIBLE (-9600 9500);
FORCEADD OFFPAGE_BI..1
R 6
(-9600 9300);
FORCEPROP 2 LAST $XR0 24J7< 
J 0
(-9540 9300);
DISPLAY 0.638298 (-9540 9300);
PAINT MONO (-9540 9300);
FORCEPROP 1 LAST BODY_TYPE COMMENT
J 0
(-9590 9127);
DISPLAY 0.808511 (-9590 9127);
PAINT GREEN (-9590 9127);
DISPLAY INVISIBLE (-9590 9127);
FORCEPROP 1 LAST OFFPAGE TRUE
J 0
(-9590 9207);
DISPLAY 0.808511 (-9590 9207);
PAINT GREEN (-9590 9207);
DISPLAY INVISIBLE (-9590 9207);
FORCEPROP 2 LAST PATH I1618
J 0
(-9550 9400);
DISPLAY 1.021277 (-9550 9400);
DISPLAY INVISIBLE (-9550 9400);
FORCEPROP 1 LAST CDS_LMAN_SYM_OUTLINE -50,50,50,-50
J 0
(-9600 9300);
DISPLAY 0.468085 (-9600 9300);
PAINT GREEN (-9600 9300);
DISPLAY INVISIBLE (-9600 9300);
FORCEPROP 2 LAST CDS_LIB cls
J 0
(-9600 9300);
DISPLAY INVISIBLE (-9600 9300);
FORCEADD OFFPAGE_BI..1
R 6
(-9600 9400);
FORCEPROP 2 LAST $XR0 24K13< 
J 0
(-9540 9400);
DISPLAY 0.638298 (-9540 9400);
PAINT MONO (-9540 9400);
FORCEPROP 1 LAST BODY_TYPE COMMENT
J 0
(-9590 9227);
DISPLAY 0.808511 (-9590 9227);
PAINT GREEN (-9590 9227);
DISPLAY INVISIBLE (-9590 9227);
FORCEPROP 1 LAST OFFPAGE TRUE
J 0
(-9590 9307);
DISPLAY 0.808511 (-9590 9307);
PAINT GREEN (-9590 9307);
DISPLAY INVISIBLE (-9590 9307);
FORCEPROP 2 LAST PATH I1619
J 0
(-9550 9500);
DISPLAY 1.021277 (-9550 9500);
DISPLAY INVISIBLE (-9550 9500);
FORCEPROP 1 LAST CDS_LMAN_SYM_OUTLINE -50,50,50,-50
J 0
(-9600 9400);
DISPLAY 0.468085 (-9600 9400);
PAINT GREEN (-9600 9400);
DISPLAY INVISIBLE (-9600 9400);
FORCEPROP 2 LAST CDS_LIB cls
J 0
(-9600 9400);
DISPLAY INVISIBLE (-9600 9400);
FORCEADD OFFPAGE_BI..1
R 6
(-9600 9200);
FORCEPROP 2 LAST $XR0 24J4< 
J 0
(-9540 9200);
DISPLAY 0.638298 (-9540 9200);
PAINT MONO (-9540 9200);
FORCEPROP 1 LAST BODY_TYPE COMMENT
J 0
(-9590 9027);
DISPLAY 0.808511 (-9590 9027);
PAINT GREEN (-9590 9027);
DISPLAY INVISIBLE (-9590 9027);
FORCEPROP 1 LAST OFFPAGE TRUE
J 0
(-9590 9107);
DISPLAY 0.808511 (-9590 9107);
PAINT GREEN (-9590 9107);
DISPLAY INVISIBLE (-9590 9107);
FORCEPROP 2 LAST PATH I1620
J 0
(-9550 9300);
DISPLAY 1.021277 (-9550 9300);
DISPLAY INVISIBLE (-9550 9300);
FORCEPROP 1 LAST CDS_LMAN_SYM_OUTLINE -50,50,50,-50
J 0
(-9600 9200);
DISPLAY 0.468085 (-9600 9200);
PAINT GREEN (-9600 9200);
DISPLAY INVISIBLE (-9600 9200);
FORCEPROP 2 LAST CDS_LIB cls
J 0
(-9600 9200);
DISPLAY INVISIBLE (-9600 9200);
FORCEADD OFFPAGE_BI..1
R 6
(-9600 9050);
FORCEPROP 2 LAST $XR0 22F9< 
J 0
(-9540 9050);
DISPLAY 0.638298 (-9540 9050);
PAINT MONO (-9540 9050);
FORCEPROP 1 LAST OFFPAGE TRUE
J 0
(-9590 8957);
DISPLAY 0.808511 (-9590 8957);
PAINT GREEN (-9590 8957);
DISPLAY INVISIBLE (-9590 8957);
FORCEPROP 1 LAST BODY_TYPE COMMENT
J 0
(-9590 8877);
DISPLAY 0.808511 (-9590 8877);
PAINT GREEN (-9590 8877);
DISPLAY INVISIBLE (-9590 8877);
FORCEPROP 2 LAST PATH I1621
J 0
(-9550 9150);
DISPLAY 1.021277 (-9550 9150);
DISPLAY INVISIBLE (-9550 9150);
FORCEPROP 2 LAST CDS_LIB cls
J 0
(-9600 9050);
DISPLAY INVISIBLE (-9600 9050);
FORCEPROP 1 LAST CDS_LMAN_SYM_OUTLINE -50,50,50,-50
J 0
(-9600 9050);
DISPLAY 0.468085 (-9600 9050);
PAINT GREEN (-9600 9050);
DISPLAY INVISIBLE (-9600 9050);
FORCEADD OFFPAGE_BI..1
R 6
(-9600 8950);
FORCEPROP 2 LAST $XR0 20F11< 
J 0
(-9540 8950);
DISPLAY 0.638298 (-9540 8950);
PAINT MONO (-9540 8950);
FORCEPROP 1 LAST OFFPAGE TRUE
J 0
(-9590 8857);
DISPLAY 0.808511 (-9590 8857);
PAINT GREEN (-9590 8857);
DISPLAY INVISIBLE (-9590 8857);
FORCEPROP 1 LAST BODY_TYPE COMMENT
J 0
(-9590 8777);
DISPLAY 0.808511 (-9590 8777);
PAINT GREEN (-9590 8777);
DISPLAY INVISIBLE (-9590 8777);
FORCEPROP 2 LAST PATH I1622
J 0
(-9550 9050);
DISPLAY 1.021277 (-9550 9050);
DISPLAY INVISIBLE (-9550 9050);
FORCEPROP 2 LAST CDS_LIB cls
J 0
(-9600 8950);
DISPLAY INVISIBLE (-9600 8950);
FORCEPROP 1 LAST CDS_LMAN_SYM_OUTLINE -50,50,50,-50
J 0
(-9600 8950);
DISPLAY 0.468085 (-9600 8950);
PAINT GREEN (-9600 8950);
DISPLAY INVISIBLE (-9600 8950);
FORCEADD OFFPAGE_BI..1
R 6
(-9600 8850);
FORCEPROP 2 LAST $XR0 20F6> 
J 0
(-9540 8850);
DISPLAY 0.638298 (-9540 8850);
PAINT MONO (-9540 8850);
FORCEPROP 1 LAST OFFPAGE TRUE
J 0
(-9590 8757);
DISPLAY 0.808511 (-9590 8757);
PAINT GREEN (-9590 8757);
DISPLAY INVISIBLE (-9590 8757);
FORCEPROP 1 LAST BODY_TYPE COMMENT
J 0
(-9590 8677);
DISPLAY 0.808511 (-9590 8677);
PAINT GREEN (-9590 8677);
DISPLAY INVISIBLE (-9590 8677);
FORCEPROP 2 LAST PATH I1623
J 0
(-9550 8950);
DISPLAY 1.021277 (-9550 8950);
DISPLAY INVISIBLE (-9550 8950);
FORCEPROP 2 LAST CDS_LIB cls
J 0
(-9600 8850);
DISPLAY INVISIBLE (-9600 8850);
FORCEPROP 1 LAST CDS_LMAN_SYM_OUTLINE -50,50,50,-50
J 0
(-9600 8850);
DISPLAY 0.468085 (-9600 8850);
PAINT GREEN (-9600 8850);
DISPLAY INVISIBLE (-9600 8850);
FORCEADD OFFPAGE_BI..1
R 6
(-9600 8750);
FORCEPROP 2 LAST $XR0 20F6< 
J 0
(-9540 8750);
DISPLAY 0.638298 (-9540 8750);
PAINT MONO (-9540 8750);
FORCEPROP 1 LAST OFFPAGE TRUE
J 0
(-9590 8657);
DISPLAY 0.808511 (-9590 8657);
PAINT GREEN (-9590 8657);
DISPLAY INVISIBLE (-9590 8657);
FORCEPROP 1 LAST BODY_TYPE COMMENT
J 0
(-9590 8577);
DISPLAY 0.808511 (-9590 8577);
PAINT GREEN (-9590 8577);
DISPLAY INVISIBLE (-9590 8577);
FORCEPROP 2 LAST PATH I1624
J 0
(-9550 8850);
DISPLAY 1.021277 (-9550 8850);
DISPLAY INVISIBLE (-9550 8850);
FORCEPROP 2 LAST CDS_LIB cls
J 0
(-9600 8750);
DISPLAY INVISIBLE (-9600 8750);
FORCEPROP 1 LAST CDS_LMAN_SYM_OUTLINE -50,50,50,-50
J 0
(-9600 8750);
DISPLAY 0.468085 (-9600 8750);
PAINT GREEN (-9600 8750);
DISPLAY INVISIBLE (-9600 8750);
FORCEADD OFFPAGE_BI..1
R 6
(-9600 8550);
FORCEPROP 2 LAST $XR0 16J12< 
J 0
(-9540 8550);
DISPLAY 0.638298 (-9540 8550);
PAINT MONO (-9540 8550);
FORCEPROP 1 LAST OFFPAGE TRUE
J 0
(-9590 8457);
DISPLAY 0.808511 (-9590 8457);
PAINT GREEN (-9590 8457);
DISPLAY INVISIBLE (-9590 8457);
FORCEPROP 1 LAST BODY_TYPE COMMENT
J 0
(-9590 8377);
DISPLAY 0.808511 (-9590 8377);
PAINT GREEN (-9590 8377);
DISPLAY INVISIBLE (-9590 8377);
FORCEPROP 2 LAST PATH I1625
J 0
(-9550 8650);
DISPLAY 1.021277 (-9550 8650);
DISPLAY INVISIBLE (-9550 8650);
FORCEPROP 2 LAST CDS_LIB cls
J 0
(-9600 8550);
DISPLAY INVISIBLE (-9600 8550);
FORCEPROP 1 LAST CDS_LMAN_SYM_OUTLINE -50,50,50,-50
J 0
(-9600 8550);
DISPLAY 0.468085 (-9600 8550);
PAINT GREEN (-9600 8550);
DISPLAY INVISIBLE (-9600 8550);
FORCEADD TP_PIONT..1
R 2
(-10950 9500);
FORCEPROP 1 LAST $LOCATION TP11
J 2
(-11100 9500);
DISPLAY 0.808511 (-11100 9500);
PAINT GREEN (-11100 9500);
FORCEPROP 0 LAST CDS_LOCATION TP11
J 0
(-11100 9550);
DISPLAY 1.021277 (-11100 9550);
DISPLAY INVISIBLE (-11100 9550);
FORCEPROP 0 LAST $SEC 1
J 0
(-11100 9550);
DISPLAY 0.680851 (-11100 9550);
PAINT MONO (-11100 9550);
DISPLAY INVISIBLE (-11100 9550);
FORCEPROP 0 LAST CDS_SEC 1
J 0
(-11100 9550);
DISPLAY 1.021277 (-11100 9550);
DISPLAY INVISIBLE (-11100 9550);
FORCEPROP 0 LASTPIN (-10850 9500) $PN 1
J 0
(-10840 9510);
DISPLAY 0.680851 (-10840 9510);
PAINT MONO (-10840 9510);
FORCEPROP 1 LAST JEDEC_TYPE TP010CT020B030_PTH
J 2
(-10826 9600);
DISPLAY 0.000000 (-10826 9600);
PAINT GREEN (-10826 9600);
DISPLAY INVISIBLE (-10826 9600);
FORCEPROP 1 LAST BOM_IGNORE TRUE
J 2
(-10826 9600);
DISPLAY 0.000000 (-10826 9600);
PAINT GREEN (-10826 9600);
DISPLAY INVISIBLE (-10826 9600);
FORCEPROP 1 LAST PATH I1626
J 2
(-11030 9613);
DISPLAY 0.808511 (-11030 9613);
PAINT GREEN (-11030 9613);
DISPLAY INVISIBLE (-11030 9613);
FORCEPROP 1 LAST CDS_LMAN_SYM_OUTLINE -50,50,50,-50
J 2
(-10950 9500);
DISPLAY 0.468085 (-10950 9500);
PAINT GREEN (-10950 9500);
DISPLAY INVISIBLE (-10950 9500);
FORCEPROP 2 LAST CDS_LIB cls
J 0
(-10950 9500);
DISPLAY INVISIBLE (-10950 9500);
FORCEADD TP_PIONT..1
R 2
(-10950 9400);
FORCEPROP 1 LAST $LOCATION TP12
J 2
(-11100 9400);
DISPLAY 0.808511 (-11100 9400);
PAINT GREEN (-11100 9400);
FORCEPROP 0 LAST CDS_LOCATION TP12
J 0
(-11100 9450);
DISPLAY 1.021277 (-11100 9450);
DISPLAY INVISIBLE (-11100 9450);
FORCEPROP 0 LAST $SEC 1
J 0
(-11100 9450);
DISPLAY 0.680851 (-11100 9450);
PAINT MONO (-11100 9450);
DISPLAY INVISIBLE (-11100 9450);
FORCEPROP 0 LAST CDS_SEC 1
J 0
(-11100 9450);
DISPLAY 1.021277 (-11100 9450);
DISPLAY INVISIBLE (-11100 9450);
FORCEPROP 0 LASTPIN (-10850 9400) $PN 1
J 0
(-10840 9410);
DISPLAY 0.680851 (-10840 9410);
PAINT MONO (-10840 9410);
FORCEPROP 1 LAST JEDEC_TYPE TP010CT020B030_PTH
J 2
(-10826 9500);
DISPLAY 0.000000 (-10826 9500);
PAINT GREEN (-10826 9500);
DISPLAY INVISIBLE (-10826 9500);
FORCEPROP 1 LAST BOM_IGNORE TRUE
J 2
(-10826 9500);
DISPLAY 0.000000 (-10826 9500);
PAINT GREEN (-10826 9500);
DISPLAY INVISIBLE (-10826 9500);
FORCEPROP 1 LAST PATH I1627
J 2
(-11030 9513);
DISPLAY 0.808511 (-11030 9513);
PAINT GREEN (-11030 9513);
DISPLAY INVISIBLE (-11030 9513);
FORCEPROP 1 LAST CDS_LMAN_SYM_OUTLINE -50,50,50,-50
J 2
(-10950 9400);
DISPLAY 0.468085 (-10950 9400);
PAINT GREEN (-10950 9400);
DISPLAY INVISIBLE (-10950 9400);
FORCEPROP 2 LAST CDS_LIB cls
J 0
(-10950 9400);
DISPLAY INVISIBLE (-10950 9400);
FORCEADD TP_PIONT..1
R 2
(-10950 9300);
FORCEPROP 1 LAST $LOCATION TP13
J 2
(-11100 9300);
DISPLAY 0.808511 (-11100 9300);
PAINT GREEN (-11100 9300);
FORCEPROP 0 LAST CDS_LOCATION TP13
J 0
(-11100 9350);
DISPLAY 1.021277 (-11100 9350);
DISPLAY INVISIBLE (-11100 9350);
FORCEPROP 0 LAST $SEC 1
J 0
(-11100 9350);
DISPLAY 0.680851 (-11100 9350);
PAINT MONO (-11100 9350);
DISPLAY INVISIBLE (-11100 9350);
FORCEPROP 0 LAST CDS_SEC 1
J 0
(-11100 9350);
DISPLAY 1.021277 (-11100 9350);
DISPLAY INVISIBLE (-11100 9350);
FORCEPROP 0 LASTPIN (-10850 9300) $PN 1
J 0
(-10840 9310);
DISPLAY 0.680851 (-10840 9310);
PAINT MONO (-10840 9310);
FORCEPROP 1 LAST JEDEC_TYPE TP010CT020B030_PTH
J 2
(-10826 9400);
DISPLAY 0.000000 (-10826 9400);
PAINT GREEN (-10826 9400);
DISPLAY INVISIBLE (-10826 9400);
FORCEPROP 1 LAST BOM_IGNORE TRUE
J 2
(-10826 9400);
DISPLAY 0.000000 (-10826 9400);
PAINT GREEN (-10826 9400);
DISPLAY INVISIBLE (-10826 9400);
FORCEPROP 1 LAST PATH I1628
J 2
(-11030 9413);
DISPLAY 0.808511 (-11030 9413);
PAINT GREEN (-11030 9413);
DISPLAY INVISIBLE (-11030 9413);
FORCEPROP 1 LAST CDS_LMAN_SYM_OUTLINE -50,50,50,-50
J 2
(-10950 9300);
DISPLAY 0.468085 (-10950 9300);
PAINT GREEN (-10950 9300);
DISPLAY INVISIBLE (-10950 9300);
FORCEPROP 2 LAST CDS_LIB cls
J 0
(-10950 9300);
DISPLAY INVISIBLE (-10950 9300);
FORCEADD TP_PIONT..1
R 2
(-10950 9200);
FORCEPROP 1 LAST $LOCATION TP14
J 2
(-11100 9200);
DISPLAY 0.808511 (-11100 9200);
PAINT GREEN (-11100 9200);
FORCEPROP 0 LAST CDS_LOCATION TP14
J 0
(-11100 9250);
DISPLAY 1.021277 (-11100 9250);
DISPLAY INVISIBLE (-11100 9250);
FORCEPROP 0 LAST $SEC 1
J 0
(-11100 9250);
DISPLAY 0.680851 (-11100 9250);
PAINT MONO (-11100 9250);
DISPLAY INVISIBLE (-11100 9250);
FORCEPROP 0 LAST CDS_SEC 1
J 0
(-11100 9250);
DISPLAY 1.021277 (-11100 9250);
DISPLAY INVISIBLE (-11100 9250);
FORCEPROP 0 LASTPIN (-10850 9200) $PN 1
J 0
(-10840 9210);
DISPLAY 0.680851 (-10840 9210);
PAINT MONO (-10840 9210);
FORCEPROP 1 LAST JEDEC_TYPE TP010CT020B030_PTH
J 2
(-10826 9300);
DISPLAY 0.000000 (-10826 9300);
PAINT GREEN (-10826 9300);
DISPLAY INVISIBLE (-10826 9300);
FORCEPROP 1 LAST BOM_IGNORE TRUE
J 2
(-10826 9300);
DISPLAY 0.000000 (-10826 9300);
PAINT GREEN (-10826 9300);
DISPLAY INVISIBLE (-10826 9300);
FORCEPROP 1 LAST PATH I1629
J 2
(-11030 9313);
DISPLAY 0.808511 (-11030 9313);
PAINT GREEN (-11030 9313);
DISPLAY INVISIBLE (-11030 9313);
FORCEPROP 1 LAST CDS_LMAN_SYM_OUTLINE -50,50,50,-50
J 2
(-10950 9200);
DISPLAY 0.468085 (-10950 9200);
PAINT GREEN (-10950 9200);
DISPLAY INVISIBLE (-10950 9200);
FORCEPROP 2 LAST CDS_LIB cls
J 0
(-10950 9200);
DISPLAY INVISIBLE (-10950 9200);
FORCEADD TP_PIONT..1
R 2
(-10950 9050);
FORCEPROP 1 LAST $LOCATION TP15
J 2
(-11100 9050);
DISPLAY 0.808511 (-11100 9050);
PAINT GREEN (-11100 9050);
FORCEPROP 0 LAST CDS_LOCATION TP15
J 0
(-11100 9100);
DISPLAY 1.021277 (-11100 9100);
DISPLAY INVISIBLE (-11100 9100);
FORCEPROP 0 LAST $SEC 1
J 0
(-11100 9100);
DISPLAY 0.680851 (-11100 9100);
PAINT MONO (-11100 9100);
DISPLAY INVISIBLE (-11100 9100);
FORCEPROP 0 LAST CDS_SEC 1
J 0
(-11100 9100);
DISPLAY 1.021277 (-11100 9100);
DISPLAY INVISIBLE (-11100 9100);
FORCEPROP 0 LASTPIN (-10850 9050) $PN 1
J 0
(-10840 9060);
DISPLAY 0.680851 (-10840 9060);
PAINT MONO (-10840 9060);
FORCEPROP 1 LAST BOM_IGNORE TRUE
J 2
(-10826 9150);
DISPLAY 0.000000 (-10826 9150);
PAINT GREEN (-10826 9150);
DISPLAY INVISIBLE (-10826 9150);
FORCEPROP 1 LAST JEDEC_TYPE TP010CT020B030_PTH
J 2
(-10826 9150);
DISPLAY 0.000000 (-10826 9150);
PAINT GREEN (-10826 9150);
DISPLAY INVISIBLE (-10826 9150);
FORCEPROP 1 LAST PATH I1630
J 2
(-11030 9163);
DISPLAY 0.808511 (-11030 9163);
PAINT GREEN (-11030 9163);
DISPLAY INVISIBLE (-11030 9163);
FORCEPROP 2 LAST CDS_LIB cls
J 0
(-10950 9050);
DISPLAY INVISIBLE (-10950 9050);
FORCEPROP 1 LAST CDS_LMAN_SYM_OUTLINE -50,50,50,-50
J 2
(-10950 9050);
DISPLAY 0.468085 (-10950 9050);
PAINT GREEN (-10950 9050);
DISPLAY INVISIBLE (-10950 9050);
FORCEADD TP_PIONT..1
R 2
(-10950 8950);
FORCEPROP 1 LAST $LOCATION TP16
J 2
(-11100 8950);
DISPLAY 0.808511 (-11100 8950);
PAINT GREEN (-11100 8950);
FORCEPROP 0 LAST CDS_LOCATION TP16
J 0
(-11100 9000);
DISPLAY 1.021277 (-11100 9000);
DISPLAY INVISIBLE (-11100 9000);
FORCEPROP 0 LAST $SEC 1
J 0
(-11100 9000);
DISPLAY 0.680851 (-11100 9000);
PAINT MONO (-11100 9000);
DISPLAY INVISIBLE (-11100 9000);
FORCEPROP 0 LAST CDS_SEC 1
J 0
(-11100 9000);
DISPLAY 1.021277 (-11100 9000);
DISPLAY INVISIBLE (-11100 9000);
FORCEPROP 0 LASTPIN (-10850 8950) $PN 1
J 0
(-10840 8960);
DISPLAY 0.680851 (-10840 8960);
PAINT MONO (-10840 8960);
FORCEPROP 1 LAST BOM_IGNORE TRUE
J 2
(-10826 9050);
DISPLAY 0.000000 (-10826 9050);
PAINT GREEN (-10826 9050);
DISPLAY INVISIBLE (-10826 9050);
FORCEPROP 1 LAST JEDEC_TYPE TP010CT020B030_PTH
J 2
(-10826 9050);
DISPLAY 0.000000 (-10826 9050);
PAINT GREEN (-10826 9050);
DISPLAY INVISIBLE (-10826 9050);
FORCEPROP 1 LAST PATH I1631
J 2
(-11030 9063);
DISPLAY 0.808511 (-11030 9063);
PAINT GREEN (-11030 9063);
DISPLAY INVISIBLE (-11030 9063);
FORCEPROP 2 LAST CDS_LIB cls
J 0
(-10950 8950);
DISPLAY INVISIBLE (-10950 8950);
FORCEPROP 1 LAST CDS_LMAN_SYM_OUTLINE -50,50,50,-50
J 2
(-10950 8950);
DISPLAY 0.468085 (-10950 8950);
PAINT GREEN (-10950 8950);
DISPLAY INVISIBLE (-10950 8950);
FORCEADD TP_PIONT..1
R 2
(-10950 8850);
FORCEPROP 1 LAST $LOCATION TP17
J 2
(-11100 8850);
DISPLAY 0.808511 (-11100 8850);
PAINT GREEN (-11100 8850);
FORCEPROP 0 LAST CDS_LOCATION TP17
J 0
(-11100 8900);
DISPLAY 1.021277 (-11100 8900);
DISPLAY INVISIBLE (-11100 8900);
FORCEPROP 0 LAST $SEC 1
J 0
(-11100 8900);
DISPLAY 0.680851 (-11100 8900);
PAINT MONO (-11100 8900);
DISPLAY INVISIBLE (-11100 8900);
FORCEPROP 0 LAST CDS_SEC 1
J 0
(-11100 8900);
DISPLAY 1.021277 (-11100 8900);
DISPLAY INVISIBLE (-11100 8900);
FORCEPROP 0 LASTPIN (-10850 8850) $PN 1
J 0
(-10840 8860);
DISPLAY 0.680851 (-10840 8860);
PAINT MONO (-10840 8860);
FORCEPROP 1 LAST BOM_IGNORE TRUE
J 2
(-10826 8950);
DISPLAY 0.000000 (-10826 8950);
PAINT GREEN (-10826 8950);
DISPLAY INVISIBLE (-10826 8950);
FORCEPROP 1 LAST JEDEC_TYPE TP010CT020B030_PTH
J 2
(-10826 8950);
DISPLAY 0.000000 (-10826 8950);
PAINT GREEN (-10826 8950);
DISPLAY INVISIBLE (-10826 8950);
FORCEPROP 1 LAST PATH I1632
J 2
(-11030 8963);
DISPLAY 0.808511 (-11030 8963);
PAINT GREEN (-11030 8963);
DISPLAY INVISIBLE (-11030 8963);
FORCEPROP 2 LAST CDS_LIB cls
J 0
(-10950 8850);
DISPLAY INVISIBLE (-10950 8850);
FORCEPROP 1 LAST CDS_LMAN_SYM_OUTLINE -50,50,50,-50
J 2
(-10950 8850);
DISPLAY 0.468085 (-10950 8850);
PAINT GREEN (-10950 8850);
DISPLAY INVISIBLE (-10950 8850);
FORCEADD TP_PIONT..1
R 2
(-10950 8750);
FORCEPROP 1 LAST $LOCATION TP18
J 2
(-11100 8750);
DISPLAY 0.808511 (-11100 8750);
PAINT GREEN (-11100 8750);
FORCEPROP 0 LAST CDS_LOCATION TP18
J 0
(-11100 8800);
DISPLAY 1.021277 (-11100 8800);
DISPLAY INVISIBLE (-11100 8800);
FORCEPROP 0 LAST $SEC 1
J 0
(-11100 8800);
DISPLAY 0.680851 (-11100 8800);
PAINT MONO (-11100 8800);
DISPLAY INVISIBLE (-11100 8800);
FORCEPROP 0 LAST CDS_SEC 1
J 0
(-11100 8800);
DISPLAY 1.021277 (-11100 8800);
DISPLAY INVISIBLE (-11100 8800);
FORCEPROP 0 LASTPIN (-10850 8750) $PN 1
J 0
(-10840 8760);
DISPLAY 0.680851 (-10840 8760);
PAINT MONO (-10840 8760);
FORCEPROP 1 LAST BOM_IGNORE TRUE
J 2
(-10826 8850);
DISPLAY 0.000000 (-10826 8850);
PAINT GREEN (-10826 8850);
DISPLAY INVISIBLE (-10826 8850);
FORCEPROP 1 LAST JEDEC_TYPE TP010CT020B030_PTH
J 2
(-10826 8850);
DISPLAY 0.000000 (-10826 8850);
PAINT GREEN (-10826 8850);
DISPLAY INVISIBLE (-10826 8850);
FORCEPROP 1 LAST PATH I1633
J 2
(-11030 8863);
DISPLAY 0.808511 (-11030 8863);
PAINT GREEN (-11030 8863);
DISPLAY INVISIBLE (-11030 8863);
FORCEPROP 2 LAST CDS_LIB cls
J 0
(-10950 8750);
DISPLAY INVISIBLE (-10950 8750);
FORCEPROP 1 LAST CDS_LMAN_SYM_OUTLINE -50,50,50,-50
J 2
(-10950 8750);
DISPLAY 0.468085 (-10950 8750);
PAINT GREEN (-10950 8750);
DISPLAY INVISIBLE (-10950 8750);
FORCEADD TP_PIONT..1
R 2
(-10950 8650);
FORCEPROP 1 LAST $LOCATION TP19
J 2
(-11100 8650);
DISPLAY 0.808511 (-11100 8650);
PAINT GREEN (-11100 8650);
FORCEPROP 0 LAST CDS_LOCATION TP19
J 0
(-11100 8700);
DISPLAY 1.021277 (-11100 8700);
DISPLAY INVISIBLE (-11100 8700);
FORCEPROP 0 LAST $SEC 1
J 0
(-11100 8700);
DISPLAY 0.680851 (-11100 8700);
PAINT MONO (-11100 8700);
DISPLAY INVISIBLE (-11100 8700);
FORCEPROP 0 LAST CDS_SEC 1
J 0
(-11100 8700);
DISPLAY 1.021277 (-11100 8700);
DISPLAY INVISIBLE (-11100 8700);
FORCEPROP 0 LASTPIN (-10850 8650) $PN 1
J 0
(-10840 8660);
DISPLAY 0.680851 (-10840 8660);
PAINT MONO (-10840 8660);
FORCEPROP 1 LAST BOM_IGNORE TRUE
J 2
(-10826 8750);
DISPLAY 0.000000 (-10826 8750);
PAINT GREEN (-10826 8750);
DISPLAY INVISIBLE (-10826 8750);
FORCEPROP 1 LAST JEDEC_TYPE TP010CT020B030_PTH
J 2
(-10826 8750);
DISPLAY 0.000000 (-10826 8750);
PAINT GREEN (-10826 8750);
DISPLAY INVISIBLE (-10826 8750);
FORCEPROP 1 LAST PATH I1634
J 2
(-11030 8763);
DISPLAY 0.808511 (-11030 8763);
PAINT GREEN (-11030 8763);
DISPLAY INVISIBLE (-11030 8763);
FORCEPROP 2 LAST CDS_LIB cls
J 0
(-10950 8650);
DISPLAY INVISIBLE (-10950 8650);
FORCEPROP 1 LAST CDS_LMAN_SYM_OUTLINE -50,50,50,-50
J 2
(-10950 8650);
DISPLAY 0.468085 (-10950 8650);
PAINT GREEN (-10950 8650);
DISPLAY INVISIBLE (-10950 8650);
FORCEADD OFFPAGE_BI..1
R 6
(-9600 8250);
FORCEPROP 2 LAST $XR0 17K12> 
J 0
(-9540 8250);
DISPLAY 0.638298 (-9540 8250);
PAINT MONO (-9540 8250);
FORCEPROP 2 LAST $XR1 12G5< 
J 0
(-9330 8250);
DISPLAY 0.638298 (-9330 8250);
PAINT MONO (-9330 8250);
FORCEPROP 1 LAST OFFPAGE TRUE
J 0
(-9590 8157);
DISPLAY 0.808511 (-9590 8157);
PAINT GREEN (-9590 8157);
DISPLAY INVISIBLE (-9590 8157);
FORCEPROP 1 LAST BODY_TYPE COMMENT
J 0
(-9590 8077);
DISPLAY 0.808511 (-9590 8077);
PAINT GREEN (-9590 8077);
DISPLAY INVISIBLE (-9590 8077);
FORCEPROP 1 LAST CDS_LMAN_SYM_OUTLINE -50,50,50,-50
J 0
(-9600 8250);
DISPLAY 0.468085 (-9600 8250);
PAINT GREEN (-9600 8250);
DISPLAY INVISIBLE (-9600 8250);
FORCEPROP 2 LAST PATH I1635
J 0
(-9550 8350);
DISPLAY 1.021277 (-9550 8350);
DISPLAY INVISIBLE (-9550 8350);
FORCEPROP 2 LAST CDS_LIB cls
J 0
(-9600 8250);
DISPLAY INVISIBLE (-9600 8250);
FORCEADD OFFPAGE_BI..1
R 6
(-9600 8350);
FORCEPROP 2 LAST $XR0 16C8< 
J 0
(-9540 8350);
DISPLAY 0.638298 (-9540 8350);
PAINT MONO (-9540 8350);
FORCEPROP 1 LAST OFFPAGE TRUE
J 0
(-9590 8257);
DISPLAY 0.808511 (-9590 8257);
PAINT GREEN (-9590 8257);
DISPLAY INVISIBLE (-9590 8257);
FORCEPROP 1 LAST BODY_TYPE COMMENT
J 0
(-9590 8177);
DISPLAY 0.808511 (-9590 8177);
PAINT GREEN (-9590 8177);
DISPLAY INVISIBLE (-9590 8177);
FORCEPROP 1 LAST CDS_LMAN_SYM_OUTLINE -50,50,50,-50
J 0
(-9600 8350);
DISPLAY 0.468085 (-9600 8350);
PAINT GREEN (-9600 8350);
DISPLAY INVISIBLE (-9600 8350);
FORCEPROP 2 LAST PATH I1636
J 0
(-9550 8450);
DISPLAY 1.021277 (-9550 8450);
DISPLAY INVISIBLE (-9550 8450);
FORCEPROP 2 LAST CDS_LIB cls
J 0
(-9600 8350);
DISPLAY INVISIBLE (-9600 8350);
FORCEADD OFFPAGE_BI..1
R 6
(-9600 8150);
FORCEPROP 2 LAST $XR1 12G5< 
J 0
(-9330 8150);
DISPLAY 0.638298 (-9330 8150);
PAINT MONO (-9330 8150);
FORCEPROP 2 LAST $XR0 17G12> 
J 0
(-9540 8150);
DISPLAY 0.638298 (-9540 8150);
PAINT MONO (-9540 8150);
FORCEPROP 1 LAST OFFPAGE TRUE
J 0
(-9590 8057);
DISPLAY 0.808511 (-9590 8057);
PAINT GREEN (-9590 8057);
DISPLAY INVISIBLE (-9590 8057);
FORCEPROP 1 LAST BODY_TYPE COMMENT
J 0
(-9590 7977);
DISPLAY 0.808511 (-9590 7977);
PAINT GREEN (-9590 7977);
DISPLAY INVISIBLE (-9590 7977);
FORCEPROP 1 LAST CDS_LMAN_SYM_OUTLINE -50,50,50,-50
J 0
(-9600 8150);
DISPLAY 0.468085 (-9600 8150);
PAINT GREEN (-9600 8150);
DISPLAY INVISIBLE (-9600 8150);
FORCEPROP 2 LAST PATH I1637
J 0
(-9550 8250);
DISPLAY 1.021277 (-9550 8250);
DISPLAY INVISIBLE (-9550 8250);
FORCEPROP 2 LAST CDS_LIB cls
J 0
(-9600 8150);
DISPLAY INVISIBLE (-9600 8150);
FORCEADD OFFPAGE_BI..1
R 6
(-9600 8050);
FORCEPROP 2 LAST $XR1 12F5< 
J 0
(-9330 8050);
DISPLAY 0.638298 (-9330 8050);
PAINT MONO (-9330 8050);
FORCEPROP 2 LAST $XR0 17D12> 
J 0
(-9540 8050);
DISPLAY 0.638298 (-9540 8050);
PAINT MONO (-9540 8050);
FORCEPROP 1 LAST OFFPAGE TRUE
J 0
(-9590 7957);
DISPLAY 0.808511 (-9590 7957);
PAINT GREEN (-9590 7957);
DISPLAY INVISIBLE (-9590 7957);
FORCEPROP 1 LAST BODY_TYPE COMMENT
J 0
(-9590 7877);
DISPLAY 0.808511 (-9590 7877);
PAINT GREEN (-9590 7877);
DISPLAY INVISIBLE (-9590 7877);
FORCEPROP 1 LAST CDS_LMAN_SYM_OUTLINE -50,50,50,-50
J 0
(-9600 8050);
DISPLAY 0.468085 (-9600 8050);
PAINT GREEN (-9600 8050);
DISPLAY INVISIBLE (-9600 8050);
FORCEPROP 2 LAST PATH I1638
J 0
(-9550 8150);
DISPLAY 1.021277 (-9550 8150);
DISPLAY INVISIBLE (-9550 8150);
FORCEPROP 2 LAST CDS_LIB cls
J 0
(-9600 8050);
DISPLAY INVISIBLE (-9600 8050);
FORCEADD OFFPAGE_BI..1
R 6
(-9600 6400);
FORCEPROP 2 LAST $XR0 27F11< 
J 0
(-9540 6400);
DISPLAY 0.638298 (-9540 6400);
PAINT MONO (-9540 6400);
FORCEPROP 2 LAST CDS_LIB cls
J 0
(-9600 6400);
DISPLAY INVISIBLE (-9600 6400);
FORCEPROP 2 LAST PATH I1639
J 0
(-9550 6500);
DISPLAY 1.021277 (-9550 6500);
DISPLAY INVISIBLE (-9550 6500);
FORCEPROP 1 LAST CDS_LMAN_SYM_OUTLINE -50,50,50,-50
J 0
(-9600 6400);
DISPLAY 0.468085 (-9600 6400);
PAINT GREEN (-9600 6400);
DISPLAY INVISIBLE (-9600 6400);
FORCEPROP 1 LAST BODY_TYPE COMMENT
J 0
(-9590 6227);
DISPLAY 0.808511 (-9590 6227);
PAINT GREEN (-9590 6227);
DISPLAY INVISIBLE (-9590 6227);
FORCEPROP 1 LAST OFFPAGE TRUE
J 0
(-9590 6307);
DISPLAY 0.808511 (-9590 6307);
PAINT GREEN (-9590 6307);
DISPLAY INVISIBLE (-9590 6307);
FORCEADD OFFPAGE_BI..1
R 6
(-9600 7900);
FORCEPROP 2 LAST $XR0 26K6< 
J 0
(-9540 7900);
DISPLAY 0.638298 (-9540 7900);
PAINT MONO (-9540 7900);
FORCEPROP 1 LAST OFFPAGE TRUE
J 0
(-9590 7807);
DISPLAY 0.808511 (-9590 7807);
PAINT GREEN (-9590 7807);
DISPLAY INVISIBLE (-9590 7807);
FORCEPROP 1 LAST BODY_TYPE COMMENT
J 0
(-9590 7727);
DISPLAY 0.808511 (-9590 7727);
PAINT GREEN (-9590 7727);
DISPLAY INVISIBLE (-9590 7727);
FORCEPROP 1 LAST CDS_LMAN_SYM_OUTLINE -50,50,50,-50
J 0
(-9600 7900);
DISPLAY 0.468085 (-9600 7900);
PAINT GREEN (-9600 7900);
DISPLAY INVISIBLE (-9600 7900);
FORCEPROP 2 LAST PATH I1640
J 0
(-9550 8000);
DISPLAY 1.021277 (-9550 8000);
DISPLAY INVISIBLE (-9550 8000);
FORCEPROP 2 LAST CDS_LIB cls
J 0
(-9600 7900);
DISPLAY INVISIBLE (-9600 7900);
FORCEADD OFFPAGE_BI..1
R 6
(-9600 5900);
FORCEPROP 2 LAST $XR1 30J2< 
J 0
(-9330 5900);
DISPLAY 0.638298 (-9330 5900);
PAINT MONO (-9330 5900);
FORCEPROP 2 LAST $XR0 30E11> 
J 0
(-9540 5900);
DISPLAY 0.638298 (-9540 5900);
PAINT MONO (-9540 5900);
FORCEPROP 1 LAST OFFPAGE TRUE
J 0
(-9590 5807);
DISPLAY 0.808511 (-9590 5807);
PAINT GREEN (-9590 5807);
DISPLAY INVISIBLE (-9590 5807);
FORCEPROP 1 LAST BODY_TYPE COMMENT
J 0
(-9590 5727);
DISPLAY 0.808511 (-9590 5727);
PAINT GREEN (-9590 5727);
DISPLAY INVISIBLE (-9590 5727);
FORCEPROP 1 LAST CDS_LMAN_SYM_OUTLINE -50,50,50,-50
J 0
(-9600 5900);
DISPLAY 0.468085 (-9600 5900);
PAINT GREEN (-9600 5900);
DISPLAY INVISIBLE (-9600 5900);
FORCEPROP 2 LAST PATH I1641
J 0
(-9550 6000);
DISPLAY 1.021277 (-9550 6000);
DISPLAY INVISIBLE (-9550 6000);
FORCEPROP 2 LAST CDS_LIB cls
J 0
(-9600 5900);
DISPLAY INVISIBLE (-9600 5900);
FORCEADD OFFPAGE_BI..1
R 6
(-9600 6100);
FORCEPROP 2 LAST $XR1 29E1< 
J 0
(-9360 6100);
DISPLAY 0.638298 (-9360 6100);
PAINT MONO (-9360 6100);
FORCEPROP 2 LAST $XR0 28H6> 
J 0
(-9540 6100);
DISPLAY 0.638298 (-9540 6100);
PAINT MONO (-9540 6100);
FORCEPROP 1 LAST BODY_TYPE COMMENT
J 0
(-9590 5927);
DISPLAY 0.808511 (-9590 5927);
PAINT GREEN (-9590 5927);
DISPLAY INVISIBLE (-9590 5927);
FORCEPROP 1 LAST OFFPAGE TRUE
J 0
(-9590 6007);
DISPLAY 0.808511 (-9590 6007);
PAINT GREEN (-9590 6007);
DISPLAY INVISIBLE (-9590 6007);
FORCEPROP 2 LAST PATH I1642
J 0
(-9550 6200);
DISPLAY 1.021277 (-9550 6200);
DISPLAY INVISIBLE (-9550 6200);
FORCEPROP 2 LAST CDS_LIB cls
J 0
(-9600 6100);
DISPLAY INVISIBLE (-9600 6100);
FORCEPROP 1 LAST CDS_LMAN_SYM_OUTLINE -50,50,50,-50
J 0
(-9600 6100);
DISPLAY 0.468085 (-9600 6100);
PAINT GREEN (-9600 6100);
DISPLAY INVISIBLE (-9600 6100);
FORCEADD OFFPAGE_BI..1
R 6
(-9600 6000);
FORCEPROP 2 LAST $XR1 30D2< 
J 0
(-9360 6000);
DISPLAY 0.638298 (-9360 6000);
PAINT MONO (-9360 6000);
FORCEPROP 2 LAST $XR0 29G1> 
J 0
(-9540 6000);
DISPLAY 0.638298 (-9540 6000);
PAINT MONO (-9540 6000);
FORCEPROP 1 LAST OFFPAGE TRUE
J 0
(-9590 5907);
DISPLAY 0.808511 (-9590 5907);
PAINT GREEN (-9590 5907);
DISPLAY INVISIBLE (-9590 5907);
FORCEPROP 1 LAST BODY_TYPE COMMENT
J 0
(-9590 5827);
DISPLAY 0.808511 (-9590 5827);
PAINT GREEN (-9590 5827);
DISPLAY INVISIBLE (-9590 5827);
FORCEPROP 1 LAST CDS_LMAN_SYM_OUTLINE -50,50,50,-50
J 0
(-9600 6000);
DISPLAY 0.468085 (-9600 6000);
PAINT GREEN (-9600 6000);
DISPLAY INVISIBLE (-9600 6000);
FORCEPROP 2 LAST PATH I1643
J 0
(-9550 6100);
DISPLAY 1.021277 (-9550 6100);
DISPLAY INVISIBLE (-9550 6100);
FORCEPROP 2 LAST CDS_LIB cls
J 0
(-9600 6000);
DISPLAY INVISIBLE (-9600 6000);
FORCEADD OFFPAGE_BI..1
R 6
(-9600 5800);
FORCEPROP 2 LAST $XR3 32E2< 
J 0
(-8970 5800);
DISPLAY 0.638298 (-8970 5800);
PAINT MONO (-8970 5800);
FORCEPROP 2 LAST $XR2 31J2< 
J 0
(-9150 5800);
DISPLAY 0.638298 (-9150 5800);
PAINT MONO (-9150 5800);
FORCEPROP 2 LAST $XR1 31D3< 
J 0
(-9330 5800);
DISPLAY 0.638298 (-9330 5800);
PAINT MONO (-9330 5800);
FORCEPROP 2 LAST $XR0 30K11> 
J 0
(-9540 5800);
DISPLAY 0.638298 (-9540 5800);
PAINT MONO (-9540 5800);
FORCEPROP 1 LAST OFFPAGE TRUE
J 0
(-9590 5707);
DISPLAY 0.808511 (-9590 5707);
PAINT GREEN (-9590 5707);
DISPLAY INVISIBLE (-9590 5707);
FORCEPROP 1 LAST BODY_TYPE COMMENT
J 0
(-9590 5627);
DISPLAY 0.808511 (-9590 5627);
PAINT GREEN (-9590 5627);
DISPLAY INVISIBLE (-9590 5627);
FORCEPROP 1 LAST CDS_LMAN_SYM_OUTLINE -50,50,50,-50
J 0
(-9600 5800);
DISPLAY 0.468085 (-9600 5800);
PAINT GREEN (-9600 5800);
DISPLAY INVISIBLE (-9600 5800);
FORCEPROP 2 LAST PATH I1644
J 0
(-9550 5900);
DISPLAY 1.021277 (-9550 5900);
DISPLAY INVISIBLE (-9550 5900);
FORCEPROP 2 LAST CDS_LIB cls
J 0
(-9600 5800);
DISPLAY INVISIBLE (-9600 5800);
FORCEADD TP_PIONT..1
R 2
(-10950 8350);
FORCEPROP 1 LAST $LOCATION TP21
J 2
(-11100 8350);
DISPLAY 0.808511 (-11100 8350);
PAINT GREEN (-11100 8350);
FORCEPROP 0 LAST CDS_LOCATION TP21
J 0
(-11100 8400);
DISPLAY 1.021277 (-11100 8400);
DISPLAY INVISIBLE (-11100 8400);
FORCEPROP 0 LAST $SEC 1
J 0
(-11100 8400);
DISPLAY 0.680851 (-11100 8400);
PAINT MONO (-11100 8400);
DISPLAY INVISIBLE (-11100 8400);
FORCEPROP 0 LAST CDS_SEC 1
J 0
(-11100 8400);
DISPLAY 1.021277 (-11100 8400);
DISPLAY INVISIBLE (-11100 8400);
FORCEPROP 0 LASTPIN (-10850 8350) $PN 1
J 0
(-10840 8360);
DISPLAY 0.680851 (-10840 8360);
PAINT MONO (-10840 8360);
FORCEPROP 1 LAST BOM_IGNORE TRUE
J 2
(-10826 8450);
DISPLAY 0.000000 (-10826 8450);
PAINT GREEN (-10826 8450);
DISPLAY INVISIBLE (-10826 8450);
FORCEPROP 1 LAST JEDEC_TYPE TP010CT020B030_PTH
J 2
(-10826 8450);
DISPLAY 0.000000 (-10826 8450);
PAINT GREEN (-10826 8450);
DISPLAY INVISIBLE (-10826 8450);
FORCEPROP 1 LAST CDS_LMAN_SYM_OUTLINE -50,50,50,-50
J 2
(-10950 8350);
DISPLAY 0.468085 (-10950 8350);
PAINT GREEN (-10950 8350);
DISPLAY INVISIBLE (-10950 8350);
FORCEPROP 1 LAST PATH I1645
J 2
(-11030 8463);
DISPLAY 0.808511 (-11030 8463);
PAINT GREEN (-11030 8463);
DISPLAY INVISIBLE (-11030 8463);
FORCEPROP 2 LAST CDS_LIB cls
J 0
(-10950 8350);
DISPLAY INVISIBLE (-10950 8350);
FORCEADD TP_PIONT..1
R 2
(-10950 8250);
FORCEPROP 1 LAST $LOCATION TP22
J 2
(-11100 8250);
DISPLAY 0.808511 (-11100 8250);
PAINT GREEN (-11100 8250);
FORCEPROP 0 LAST CDS_LOCATION TP22
J 0
(-11100 8300);
DISPLAY 1.021277 (-11100 8300);
DISPLAY INVISIBLE (-11100 8300);
FORCEPROP 0 LAST $SEC 1
J 0
(-11100 8300);
DISPLAY 0.680851 (-11100 8300);
PAINT MONO (-11100 8300);
DISPLAY INVISIBLE (-11100 8300);
FORCEPROP 0 LAST CDS_SEC 1
J 0
(-11100 8300);
DISPLAY 1.021277 (-11100 8300);
DISPLAY INVISIBLE (-11100 8300);
FORCEPROP 0 LASTPIN (-10850 8250) $PN 1
J 0
(-10840 8260);
DISPLAY 0.680851 (-10840 8260);
PAINT MONO (-10840 8260);
FORCEPROP 1 LAST BOM_IGNORE TRUE
J 2
(-10826 8350);
DISPLAY 0.000000 (-10826 8350);
PAINT GREEN (-10826 8350);
DISPLAY INVISIBLE (-10826 8350);
FORCEPROP 1 LAST JEDEC_TYPE TP010CT020B030_PTH
J 2
(-10826 8350);
DISPLAY 0.000000 (-10826 8350);
PAINT GREEN (-10826 8350);
DISPLAY INVISIBLE (-10826 8350);
FORCEPROP 1 LAST CDS_LMAN_SYM_OUTLINE -50,50,50,-50
J 2
(-10950 8250);
DISPLAY 0.468085 (-10950 8250);
PAINT GREEN (-10950 8250);
DISPLAY INVISIBLE (-10950 8250);
FORCEPROP 1 LAST PATH I1646
J 2
(-11030 8363);
DISPLAY 0.808511 (-11030 8363);
PAINT GREEN (-11030 8363);
DISPLAY INVISIBLE (-11030 8363);
FORCEPROP 2 LAST CDS_LIB cls
J 0
(-10950 8250);
DISPLAY INVISIBLE (-10950 8250);
FORCEADD TP_PIONT..1
R 2
(-10950 8150);
FORCEPROP 1 LAST $LOCATION TP23
J 2
(-11100 8150);
DISPLAY 0.808511 (-11100 8150);
PAINT GREEN (-11100 8150);
FORCEPROP 0 LAST CDS_LOCATION TP23
J 0
(-11100 8200);
DISPLAY 1.021277 (-11100 8200);
DISPLAY INVISIBLE (-11100 8200);
FORCEPROP 0 LAST $SEC 1
J 0
(-11100 8200);
DISPLAY 0.680851 (-11100 8200);
PAINT MONO (-11100 8200);
DISPLAY INVISIBLE (-11100 8200);
FORCEPROP 0 LAST CDS_SEC 1
J 0
(-11100 8200);
DISPLAY 1.021277 (-11100 8200);
DISPLAY INVISIBLE (-11100 8200);
FORCEPROP 0 LASTPIN (-10850 8150) $PN 1
J 0
(-10840 8160);
DISPLAY 0.680851 (-10840 8160);
PAINT MONO (-10840 8160);
FORCEPROP 1 LAST BOM_IGNORE TRUE
J 2
(-10826 8250);
DISPLAY 0.000000 (-10826 8250);
PAINT GREEN (-10826 8250);
DISPLAY INVISIBLE (-10826 8250);
FORCEPROP 1 LAST JEDEC_TYPE TP010CT020B030_PTH
J 2
(-10826 8250);
DISPLAY 0.000000 (-10826 8250);
PAINT GREEN (-10826 8250);
DISPLAY INVISIBLE (-10826 8250);
FORCEPROP 1 LAST CDS_LMAN_SYM_OUTLINE -50,50,50,-50
J 2
(-10950 8150);
DISPLAY 0.468085 (-10950 8150);
PAINT GREEN (-10950 8150);
DISPLAY INVISIBLE (-10950 8150);
FORCEPROP 1 LAST PATH I1647
J 2
(-11030 8263);
DISPLAY 0.808511 (-11030 8263);
PAINT GREEN (-11030 8263);
DISPLAY INVISIBLE (-11030 8263);
FORCEPROP 2 LAST CDS_LIB cls
J 0
(-10950 8150);
DISPLAY INVISIBLE (-10950 8150);
FORCEADD TP_PIONT..1
R 2
(-10950 8050);
FORCEPROP 1 LAST $LOCATION TP24
J 2
(-11100 8050);
DISPLAY 0.808511 (-11100 8050);
PAINT GREEN (-11100 8050);
FORCEPROP 0 LAST CDS_LOCATION TP24
J 0
(-11100 8100);
DISPLAY 1.021277 (-11100 8100);
DISPLAY INVISIBLE (-11100 8100);
FORCEPROP 0 LAST $SEC 1
J 0
(-11100 8100);
DISPLAY 0.680851 (-11100 8100);
PAINT MONO (-11100 8100);
DISPLAY INVISIBLE (-11100 8100);
FORCEPROP 0 LAST CDS_SEC 1
J 0
(-11100 8100);
DISPLAY 1.021277 (-11100 8100);
DISPLAY INVISIBLE (-11100 8100);
FORCEPROP 0 LASTPIN (-10850 8050) $PN 1
J 0
(-10840 8060);
DISPLAY 0.680851 (-10840 8060);
PAINT MONO (-10840 8060);
FORCEPROP 1 LAST BOM_IGNORE TRUE
J 2
(-10826 8150);
DISPLAY 0.000000 (-10826 8150);
PAINT GREEN (-10826 8150);
DISPLAY INVISIBLE (-10826 8150);
FORCEPROP 1 LAST JEDEC_TYPE TP010CT020B030_PTH
J 2
(-10826 8150);
DISPLAY 0.000000 (-10826 8150);
PAINT GREEN (-10826 8150);
DISPLAY INVISIBLE (-10826 8150);
FORCEPROP 1 LAST CDS_LMAN_SYM_OUTLINE -50,50,50,-50
J 2
(-10950 8050);
DISPLAY 0.468085 (-10950 8050);
PAINT GREEN (-10950 8050);
DISPLAY INVISIBLE (-10950 8050);
FORCEPROP 1 LAST PATH I1648
J 2
(-11030 8163);
DISPLAY 0.808511 (-11030 8163);
PAINT GREEN (-11030 8163);
DISPLAY INVISIBLE (-11030 8163);
FORCEPROP 2 LAST CDS_LIB cls
J 0
(-10950 8050);
DISPLAY INVISIBLE (-10950 8050);
FORCEADD TP_PIONT..1
R 2
(-10950 7900);
FORCEPROP 1 LAST $LOCATION TP25
J 2
(-11100 7900);
DISPLAY 0.808511 (-11100 7900);
PAINT GREEN (-11100 7900);
FORCEPROP 0 LAST CDS_LOCATION TP25
J 0
(-11100 7950);
DISPLAY 1.021277 (-11100 7950);
DISPLAY INVISIBLE (-11100 7950);
FORCEPROP 0 LAST $SEC 1
J 0
(-11100 7950);
DISPLAY 0.680851 (-11100 7950);
PAINT MONO (-11100 7950);
DISPLAY INVISIBLE (-11100 7950);
FORCEPROP 0 LAST CDS_SEC 1
J 0
(-11100 7950);
DISPLAY 1.021277 (-11100 7950);
DISPLAY INVISIBLE (-11100 7950);
FORCEPROP 0 LASTPIN (-10850 7900) $PN 1
J 0
(-10840 7910);
DISPLAY 0.680851 (-10840 7910);
PAINT MONO (-10840 7910);
FORCEPROP 1 LAST BOM_IGNORE TRUE
J 2
(-10826 8000);
DISPLAY 0.000000 (-10826 8000);
PAINT GREEN (-10826 8000);
DISPLAY INVISIBLE (-10826 8000);
FORCEPROP 1 LAST JEDEC_TYPE TP010CT020B030_PTH
J 2
(-10826 8000);
DISPLAY 0.000000 (-10826 8000);
PAINT GREEN (-10826 8000);
DISPLAY INVISIBLE (-10826 8000);
FORCEPROP 1 LAST CDS_LMAN_SYM_OUTLINE -50,50,50,-50
J 2
(-10950 7900);
DISPLAY 0.468085 (-10950 7900);
PAINT GREEN (-10950 7900);
DISPLAY INVISIBLE (-10950 7900);
FORCEPROP 1 LAST PATH I1649
J 2
(-11030 8013);
DISPLAY 0.808511 (-11030 8013);
PAINT GREEN (-11030 8013);
DISPLAY INVISIBLE (-11030 8013);
FORCEPROP 2 LAST CDS_LIB cls
J 0
(-10950 7900);
DISPLAY INVISIBLE (-10950 7900);
FORCEADD TP_PIONT..1
R 2
(-10950 6400);
FORCEPROP 1 LAST $LOCATION TP36
J 2
(-11100 6400);
DISPLAY 0.808511 (-11100 6400);
PAINT GREEN (-11100 6400);
FORCEPROP 0 LAST CDS_LOCATION TP36
J 0
(-11100 6450);
DISPLAY 1.021277 (-11100 6450);
DISPLAY INVISIBLE (-11100 6450);
FORCEPROP 0 LAST $SEC 1
J 0
(-11100 6450);
DISPLAY 0.680851 (-11100 6450);
PAINT MONO (-11100 6450);
DISPLAY INVISIBLE (-11100 6450);
FORCEPROP 0 LAST CDS_SEC 1
J 0
(-11100 6450);
DISPLAY 1.021277 (-11100 6450);
DISPLAY INVISIBLE (-11100 6450);
FORCEPROP 0 LASTPIN (-10850 6400) $PN 1
J 0
(-10840 6410);
DISPLAY 0.680851 (-10840 6410);
PAINT MONO (-10840 6410);
FORCEPROP 2 LAST CDS_LIB cls
J 0
(-10950 6400);
DISPLAY INVISIBLE (-10950 6400);
FORCEPROP 1 LAST PATH I1650
J 2
(-11030 6513);
DISPLAY 0.808511 (-11030 6513);
PAINT GREEN (-11030 6513);
DISPLAY INVISIBLE (-11030 6513);
FORCEPROP 1 LAST CDS_LMAN_SYM_OUTLINE -50,50,50,-50
J 2
(-10950 6400);
DISPLAY 0.468085 (-10950 6400);
PAINT GREEN (-10950 6400);
DISPLAY INVISIBLE (-10950 6400);
FORCEPROP 1 LAST JEDEC_TYPE TP010CT020B030_PTH
J 2
(-10826 6500);
DISPLAY 0.000000 (-10826 6500);
PAINT GREEN (-10826 6500);
DISPLAY INVISIBLE (-10826 6500);
FORCEPROP 1 LAST BOM_IGNORE TRUE
J 2
(-10826 6500);
DISPLAY 0.000000 (-10826 6500);
PAINT GREEN (-10826 6500);
DISPLAY INVISIBLE (-10826 6500);
FORCEADD TP_PIONT..1
R 2
(-10950 6100);
FORCEPROP 1 LAST $LOCATION TP38
J 2
(-11100 6100);
DISPLAY 0.808511 (-11100 6100);
PAINT GREEN (-11100 6100);
FORCEPROP 0 LAST CDS_LOCATION TP38
J 0
(-11100 6150);
DISPLAY 1.021277 (-11100 6150);
DISPLAY INVISIBLE (-11100 6150);
FORCEPROP 0 LAST $SEC 1
J 0
(-11100 6150);
DISPLAY 0.680851 (-11100 6150);
PAINT MONO (-11100 6150);
DISPLAY INVISIBLE (-11100 6150);
FORCEPROP 0 LAST CDS_SEC 1
J 0
(-11100 6150);
DISPLAY 1.021277 (-11100 6150);
DISPLAY INVISIBLE (-11100 6150);
FORCEPROP 0 LASTPIN (-10850 6100) $PN 1
J 0
(-10840 6110);
DISPLAY 0.680851 (-10840 6110);
PAINT MONO (-10840 6110);
FORCEPROP 1 LAST BOM_IGNORE TRUE
J 2
(-10826 6200);
DISPLAY 0.000000 (-10826 6200);
PAINT GREEN (-10826 6200);
DISPLAY INVISIBLE (-10826 6200);
FORCEPROP 1 LAST JEDEC_TYPE TP010CT020B030_PTH
J 2
(-10826 6200);
DISPLAY 0.000000 (-10826 6200);
PAINT GREEN (-10826 6200);
DISPLAY INVISIBLE (-10826 6200);
FORCEPROP 1 LAST CDS_LMAN_SYM_OUTLINE -50,50,50,-50
J 2
(-10950 6100);
DISPLAY 0.468085 (-10950 6100);
PAINT GREEN (-10950 6100);
DISPLAY INVISIBLE (-10950 6100);
FORCEPROP 1 LAST PATH I1651
J 2
(-11030 6213);
DISPLAY 0.808511 (-11030 6213);
PAINT GREEN (-11030 6213);
DISPLAY INVISIBLE (-11030 6213);
FORCEPROP 2 LAST CDS_LIB cls
J 0
(-10950 6100);
DISPLAY INVISIBLE (-10950 6100);
FORCEADD TP_PIONT..1
R 2
(-10950 6000);
FORCEPROP 1 LAST $LOCATION TP39
J 2
(-11100 6000);
DISPLAY 0.808511 (-11100 6000);
PAINT GREEN (-11100 6000);
FORCEPROP 0 LAST CDS_LOCATION TP39
J 0
(-11100 6050);
DISPLAY 1.021277 (-11100 6050);
DISPLAY INVISIBLE (-11100 6050);
FORCEPROP 0 LAST $SEC 1
J 0
(-11100 6050);
DISPLAY 0.680851 (-11100 6050);
PAINT MONO (-11100 6050);
DISPLAY INVISIBLE (-11100 6050);
FORCEPROP 0 LAST CDS_SEC 1
J 0
(-11100 6050);
DISPLAY 1.021277 (-11100 6050);
DISPLAY INVISIBLE (-11100 6050);
FORCEPROP 0 LASTPIN (-10850 6000) $PN 1
J 0
(-10840 6010);
DISPLAY 0.680851 (-10840 6010);
PAINT MONO (-10840 6010);
FORCEPROP 1 LAST BOM_IGNORE TRUE
J 2
(-10826 6100);
DISPLAY 0.000000 (-10826 6100);
PAINT GREEN (-10826 6100);
DISPLAY INVISIBLE (-10826 6100);
FORCEPROP 1 LAST JEDEC_TYPE TP010CT020B030_PTH
J 2
(-10826 6100);
DISPLAY 0.000000 (-10826 6100);
PAINT GREEN (-10826 6100);
DISPLAY INVISIBLE (-10826 6100);
FORCEPROP 1 LAST CDS_LMAN_SYM_OUTLINE -50,50,50,-50
J 2
(-10950 6000);
DISPLAY 0.468085 (-10950 6000);
PAINT GREEN (-10950 6000);
DISPLAY INVISIBLE (-10950 6000);
FORCEPROP 1 LAST PATH I1652
J 2
(-11030 6113);
DISPLAY 0.808511 (-11030 6113);
PAINT GREEN (-11030 6113);
DISPLAY INVISIBLE (-11030 6113);
FORCEPROP 2 LAST CDS_LIB cls
J 0
(-10950 6000);
DISPLAY INVISIBLE (-10950 6000);
FORCEADD TP_PIONT..1
R 2
(-10950 5900);
FORCEPROP 1 LAST $LOCATION TP40
J 2
(-11100 5900);
DISPLAY 0.808511 (-11100 5900);
PAINT GREEN (-11100 5900);
FORCEPROP 0 LAST CDS_LOCATION TP40
J 0
(-11100 5950);
DISPLAY 1.021277 (-11100 5950);
DISPLAY INVISIBLE (-11100 5950);
FORCEPROP 0 LAST $SEC 1
J 0
(-11100 5950);
DISPLAY 0.680851 (-11100 5950);
PAINT MONO (-11100 5950);
DISPLAY INVISIBLE (-11100 5950);
FORCEPROP 0 LAST CDS_SEC 1
J 0
(-11100 5950);
DISPLAY 1.021277 (-11100 5950);
DISPLAY INVISIBLE (-11100 5950);
FORCEPROP 0 LASTPIN (-10850 5900) $PN 1
J 0
(-10840 5910);
DISPLAY 0.680851 (-10840 5910);
PAINT MONO (-10840 5910);
FORCEPROP 1 LAST BOM_IGNORE TRUE
J 2
(-10826 6000);
DISPLAY 0.000000 (-10826 6000);
PAINT GREEN (-10826 6000);
DISPLAY INVISIBLE (-10826 6000);
FORCEPROP 1 LAST JEDEC_TYPE TP010CT020B030_PTH
J 2
(-10826 6000);
DISPLAY 0.000000 (-10826 6000);
PAINT GREEN (-10826 6000);
DISPLAY INVISIBLE (-10826 6000);
FORCEPROP 1 LAST CDS_LMAN_SYM_OUTLINE -50,50,50,-50
J 2
(-10950 5900);
DISPLAY 0.468085 (-10950 5900);
PAINT GREEN (-10950 5900);
DISPLAY INVISIBLE (-10950 5900);
FORCEPROP 1 LAST PATH I1653
J 2
(-11030 6013);
DISPLAY 0.808511 (-11030 6013);
PAINT GREEN (-11030 6013);
DISPLAY INVISIBLE (-11030 6013);
FORCEPROP 2 LAST CDS_LIB cls
J 0
(-10950 5900);
DISPLAY INVISIBLE (-10950 5900);
FORCEADD TP_PIONT..1
R 2
(-10950 5800);
FORCEPROP 1 LAST $LOCATION TP41
J 2
(-11100 5800);
DISPLAY 0.808511 (-11100 5800);
PAINT GREEN (-11100 5800);
FORCEPROP 0 LAST CDS_LOCATION TP41
J 0
(-11100 5850);
DISPLAY 1.021277 (-11100 5850);
DISPLAY INVISIBLE (-11100 5850);
FORCEPROP 0 LAST $SEC 1
J 0
(-11100 5850);
DISPLAY 0.680851 (-11100 5850);
PAINT MONO (-11100 5850);
DISPLAY INVISIBLE (-11100 5850);
FORCEPROP 0 LAST CDS_SEC 1
J 0
(-11100 5850);
DISPLAY 1.021277 (-11100 5850);
DISPLAY INVISIBLE (-11100 5850);
FORCEPROP 0 LASTPIN (-10850 5800) $PN 1
J 0
(-10840 5810);
DISPLAY 0.680851 (-10840 5810);
PAINT MONO (-10840 5810);
FORCEPROP 1 LAST BOM_IGNORE TRUE
J 2
(-10826 5900);
DISPLAY 0.000000 (-10826 5900);
PAINT GREEN (-10826 5900);
DISPLAY INVISIBLE (-10826 5900);
FORCEPROP 1 LAST JEDEC_TYPE TP010CT020B030_PTH
J 2
(-10826 5900);
DISPLAY 0.000000 (-10826 5900);
PAINT GREEN (-10826 5900);
DISPLAY INVISIBLE (-10826 5900);
FORCEPROP 1 LAST CDS_LMAN_SYM_OUTLINE -50,50,50,-50
J 2
(-10950 5800);
DISPLAY 0.468085 (-10950 5800);
PAINT GREEN (-10950 5800);
DISPLAY INVISIBLE (-10950 5800);
FORCEPROP 1 LAST PATH I1654
J 2
(-11030 5913);
DISPLAY 0.808511 (-11030 5913);
PAINT GREEN (-11030 5913);
DISPLAY INVISIBLE (-11030 5913);
FORCEPROP 2 LAST CDS_LIB cls
J 0
(-10950 5800);
DISPLAY INVISIBLE (-10950 5800);
FORCEADD OFFPAGE_BI..1
R 6
(-9600 7700);
FORCEPROP 2 LAST $XR0 18G9< 
J 0
(-9540 7700);
DISPLAY 0.638298 (-9540 7700);
PAINT MONO (-9540 7700);
FORCEPROP 1 LAST BODY_TYPE COMMENT
J 0
(-9590 7527);
DISPLAY 0.808511 (-9590 7527);
PAINT GREEN (-9590 7527);
DISPLAY INVISIBLE (-9590 7527);
FORCEPROP 1 LAST OFFPAGE TRUE
J 0
(-9590 7607);
DISPLAY 0.808511 (-9590 7607);
PAINT GREEN (-9590 7607);
DISPLAY INVISIBLE (-9590 7607);
FORCEPROP 1 LAST CDS_LMAN_SYM_OUTLINE -50,50,50,-50
J 0
(-9600 7700);
DISPLAY 0.468085 (-9600 7700);
PAINT GREEN (-9600 7700);
DISPLAY INVISIBLE (-9600 7700);
FORCEPROP 2 LAST PATH I1656
J 0
(-9550 7800);
DISPLAY 1.021277 (-9550 7800);
DISPLAY INVISIBLE (-9550 7800);
FORCEPROP 2 LAST CDS_LIB cls
J 0
(-9600 7700);
DISPLAY INVISIBLE (-9600 7700);
FORCEADD OFFPAGE_BI..1
R 6
(-9600 7600);
FORCEPROP 2 LAST $XR0 18G9> 
J 0
(-9540 7600);
DISPLAY 0.638298 (-9540 7600);
PAINT MONO (-9540 7600);
FORCEPROP 1 LAST BODY_TYPE COMMENT
J 0
(-9590 7427);
DISPLAY 0.808511 (-9590 7427);
PAINT GREEN (-9590 7427);
DISPLAY INVISIBLE (-9590 7427);
FORCEPROP 1 LAST OFFPAGE TRUE
J 0
(-9590 7507);
DISPLAY 0.808511 (-9590 7507);
PAINT GREEN (-9590 7507);
DISPLAY INVISIBLE (-9590 7507);
FORCEPROP 1 LAST CDS_LMAN_SYM_OUTLINE -50,50,50,-50
J 0
(-9600 7600);
DISPLAY 0.468085 (-9600 7600);
PAINT GREEN (-9600 7600);
DISPLAY INVISIBLE (-9600 7600);
FORCEPROP 2 LAST PATH I1657
J 0
(-9550 7700);
DISPLAY 1.021277 (-9550 7700);
DISPLAY INVISIBLE (-9550 7700);
FORCEPROP 2 LAST CDS_LIB cls
J 0
(-9600 7600);
DISPLAY INVISIBLE (-9600 7600);
FORCEADD OFFPAGE_BI..1
R 6
(-9600 7000);
FORCEPROP 2 LAST $XR1 23G3< 
J 0
(-9360 7000);
DISPLAY 0.638298 (-9360 7000);
PAINT MONO (-9360 7000);
FORCEPROP 2 LAST $XR0 12G5> 
J 0
(-9540 7000);
DISPLAY 0.638298 (-9540 7000);
PAINT MONO (-9540 7000);
FORCEPROP 1 LAST BODY_TYPE COMMENT
J 0
(-9590 6827);
DISPLAY 0.808511 (-9590 6827);
PAINT GREEN (-9590 6827);
DISPLAY INVISIBLE (-9590 6827);
FORCEPROP 1 LAST OFFPAGE TRUE
J 0
(-9590 6907);
DISPLAY 0.808511 (-9590 6907);
PAINT GREEN (-9590 6907);
DISPLAY INVISIBLE (-9590 6907);
FORCEPROP 1 LAST CDS_LMAN_SYM_OUTLINE -50,50,50,-50
J 0
(-9600 7000);
DISPLAY 0.468085 (-9600 7000);
PAINT GREEN (-9600 7000);
DISPLAY INVISIBLE (-9600 7000);
FORCEPROP 2 LAST PATH I1658
J 0
(-9550 7100);
DISPLAY 1.021277 (-9550 7100);
DISPLAY INVISIBLE (-9550 7100);
FORCEPROP 2 LAST CDS_LIB cls
J 0
(-9600 7000);
DISPLAY INVISIBLE (-9600 7000);
FORCEADD TP_PIONT..1
R 2
(-10950 7700);
FORCEPROP 1 LAST $LOCATION TP26
J 2
(-11100 7700);
DISPLAY 0.808511 (-11100 7700);
PAINT GREEN (-11100 7700);
FORCEPROP 0 LAST CDS_LOCATION TP26
J 0
(-11100 7750);
DISPLAY 1.021277 (-11100 7750);
DISPLAY INVISIBLE (-11100 7750);
FORCEPROP 0 LAST $SEC 1
J 0
(-11100 7750);
DISPLAY 0.680851 (-11100 7750);
PAINT MONO (-11100 7750);
DISPLAY INVISIBLE (-11100 7750);
FORCEPROP 0 LAST CDS_SEC 1
J 0
(-11100 7750);
DISPLAY 1.021277 (-11100 7750);
DISPLAY INVISIBLE (-11100 7750);
FORCEPROP 0 LASTPIN (-10850 7700) $PN 1
J 0
(-10840 7710);
DISPLAY 0.680851 (-10840 7710);
PAINT MONO (-10840 7710);
FORCEPROP 2 LAST CDS_LIB cls
J 0
(-10950 7700);
DISPLAY INVISIBLE (-10950 7700);
FORCEPROP 1 LAST PATH I1660
J 2
(-11030 7813);
DISPLAY 0.808511 (-11030 7813);
PAINT GREEN (-11030 7813);
DISPLAY INVISIBLE (-11030 7813);
FORCEPROP 1 LAST CDS_LMAN_SYM_OUTLINE -50,50,50,-50
J 2
(-10950 7700);
DISPLAY 0.468085 (-10950 7700);
PAINT GREEN (-10950 7700);
DISPLAY INVISIBLE (-10950 7700);
FORCEPROP 1 LAST JEDEC_TYPE TP010CT020B030_PTH
J 2
(-10826 7800);
DISPLAY 0.000000 (-10826 7800);
PAINT GREEN (-10826 7800);
DISPLAY INVISIBLE (-10826 7800);
FORCEPROP 1 LAST BOM_IGNORE TRUE
J 2
(-10826 7800);
DISPLAY 0.000000 (-10826 7800);
PAINT GREEN (-10826 7800);
DISPLAY INVISIBLE (-10826 7800);
FORCEADD TP_PIONT..1
R 2
(-10950 7600);
FORCEPROP 1 LAST $LOCATION TP27
J 2
(-11100 7600);
DISPLAY 0.808511 (-11100 7600);
PAINT GREEN (-11100 7600);
FORCEPROP 0 LAST CDS_LOCATION TP27
J 0
(-11100 7650);
DISPLAY 1.021277 (-11100 7650);
DISPLAY INVISIBLE (-11100 7650);
FORCEPROP 0 LAST $SEC 1
J 0
(-11100 7650);
DISPLAY 0.680851 (-11100 7650);
PAINT MONO (-11100 7650);
DISPLAY INVISIBLE (-11100 7650);
FORCEPROP 0 LAST CDS_SEC 1
J 0
(-11100 7650);
DISPLAY 1.021277 (-11100 7650);
DISPLAY INVISIBLE (-11100 7650);
FORCEPROP 0 LASTPIN (-10850 7600) $PN 1
J 0
(-10840 7610);
DISPLAY 0.680851 (-10840 7610);
PAINT MONO (-10840 7610);
FORCEPROP 2 LAST CDS_LIB cls
J 0
(-10950 7600);
DISPLAY INVISIBLE (-10950 7600);
FORCEPROP 1 LAST PATH I1661
J 2
(-11030 7713);
DISPLAY 0.808511 (-11030 7713);
PAINT GREEN (-11030 7713);
DISPLAY INVISIBLE (-11030 7713);
FORCEPROP 1 LAST CDS_LMAN_SYM_OUTLINE -50,50,50,-50
J 2
(-10950 7600);
DISPLAY 0.468085 (-10950 7600);
PAINT GREEN (-10950 7600);
DISPLAY INVISIBLE (-10950 7600);
FORCEPROP 1 LAST JEDEC_TYPE TP010CT020B030_PTH
J 2
(-10826 7700);
DISPLAY 0.000000 (-10826 7700);
PAINT GREEN (-10826 7700);
DISPLAY INVISIBLE (-10826 7700);
FORCEPROP 1 LAST BOM_IGNORE TRUE
J 2
(-10826 7700);
DISPLAY 0.000000 (-10826 7700);
PAINT GREEN (-10826 7700);
DISPLAY INVISIBLE (-10826 7700);
FORCEADD TP_PIONT..1
R 2
(-10950 7000);
FORCEPROP 1 LAST $LOCATION TP32
J 2
(-11100 7000);
DISPLAY 0.808511 (-11100 7000);
PAINT GREEN (-11100 7000);
FORCEPROP 0 LAST CDS_LOCATION TP32
J 0
(-11100 7050);
DISPLAY 1.021277 (-11100 7050);
DISPLAY INVISIBLE (-11100 7050);
FORCEPROP 0 LAST $SEC 1
J 0
(-11100 7050);
DISPLAY 0.680851 (-11100 7050);
PAINT MONO (-11100 7050);
DISPLAY INVISIBLE (-11100 7050);
FORCEPROP 0 LAST CDS_SEC 1
J 0
(-11100 7050);
DISPLAY 1.021277 (-11100 7050);
DISPLAY INVISIBLE (-11100 7050);
FORCEPROP 0 LASTPIN (-10850 7000) $PN 1
J 0
(-10840 7010);
DISPLAY 0.680851 (-10840 7010);
PAINT MONO (-10840 7010);
FORCEPROP 2 LAST CDS_LIB cls
J 0
(-10950 7000);
DISPLAY INVISIBLE (-10950 7000);
FORCEPROP 1 LAST PATH I1662
J 2
(-11030 7113);
DISPLAY 0.808511 (-11030 7113);
PAINT GREEN (-11030 7113);
DISPLAY INVISIBLE (-11030 7113);
FORCEPROP 1 LAST CDS_LMAN_SYM_OUTLINE -50,50,50,-50
J 2
(-10950 7000);
DISPLAY 0.468085 (-10950 7000);
PAINT GREEN (-10950 7000);
DISPLAY INVISIBLE (-10950 7000);
FORCEPROP 1 LAST JEDEC_TYPE TP010CT020B030_PTH
J 2
(-10826 7100);
DISPLAY 0.000000 (-10826 7100);
PAINT GREEN (-10826 7100);
DISPLAY INVISIBLE (-10826 7100);
FORCEPROP 1 LAST BOM_IGNORE TRUE
J 2
(-10826 7100);
DISPLAY 0.000000 (-10826 7100);
PAINT GREEN (-10826 7100);
DISPLAY INVISIBLE (-10826 7100);
FORCEADD TP_PIONT..1
R 2
(-10950 6200);
FORCEPROP 1 LAST $LOCATION TP59
J 2
(-11100 6200);
DISPLAY 0.808511 (-11100 6200);
PAINT GREEN (-11100 6200);
FORCEPROP 0 LAST CDS_LOCATION TP59
J 0
(-11050 6300);
DISPLAY 1.021277 (-11050 6300);
DISPLAY INVISIBLE (-11050 6300);
FORCEPROP 0 LAST $SEC 1
J 0
(-11050 6300);
DISPLAY 0.680851 (-11050 6300);
PAINT MONO (-11050 6300);
DISPLAY INVISIBLE (-11050 6300);
FORCEPROP 0 LAST CDS_SEC 1
J 0
(-11050 6300);
DISPLAY 1.021277 (-11050 6300);
DISPLAY INVISIBLE (-11050 6300);
FORCEPROP 0 LASTPIN (-10850 6200) $PN 1
J 0
(-10840 6210);
DISPLAY 0.680851 (-10840 6210);
PAINT MONO (-10840 6210);
FORCEPROP 1 LAST PATH I1663
J 2
(-11030 6313);
DISPLAY 0.808511 (-11030 6313);
PAINT GREEN (-11030 6313);
DISPLAY INVISIBLE (-11030 6313);
FORCEPROP 2 LAST CDS_LIB cls
J 0
(-10950 6200);
DISPLAY INVISIBLE (-10950 6200);
FORCEPROP 1 LAST CDS_LMAN_SYM_OUTLINE -50,50,50,-50
J 2
(-10950 6200);
DISPLAY 0.468085 (-10950 6200);
PAINT GREEN (-10950 6200);
DISPLAY INVISIBLE (-10950 6200);
FORCEPROP 1 LAST BOM_IGNORE TRUE
J 2
(-10826 6300);
DISPLAY 0.000000 (-10826 6300);
PAINT GREEN (-10826 6300);
DISPLAY INVISIBLE (-10826 6300);
FORCEPROP 1 LAST JEDEC_TYPE TP010CT020B030_PTH
J 2
(-10826 6300);
DISPLAY 0.000000 (-10826 6300);
PAINT GREEN (-10826 6300);
DISPLAY INVISIBLE (-10826 6300);
FORCEADD OFFPAGE_BI..1
R 6
(-9600 6200);
FORCEPROP 2 LAST $XR0 28E3< 
J 0
(-9540 6200);
DISPLAY 0.638298 (-9540 6200);
PAINT MONO (-9540 6200);
FORCEPROP 2 LAST CDS_LIB cls
J 0
(-9600 6200);
DISPLAY INVISIBLE (-9600 6200);
FORCEPROP 2 LAST PATH I1664
J 0
(-9550 6300);
DISPLAY 1.021277 (-9550 6300);
DISPLAY INVISIBLE (-9550 6300);
FORCEPROP 1 LAST CDS_LMAN_SYM_OUTLINE -50,50,50,-50
J 0
(-9600 6200);
DISPLAY 0.468085 (-9600 6200);
PAINT GREEN (-9600 6200);
DISPLAY INVISIBLE (-9600 6200);
FORCEPROP 1 LAST BODY_TYPE COMMENT
J 0
(-9590 6027);
DISPLAY 0.808511 (-9590 6027);
PAINT GREEN (-9590 6027);
DISPLAY INVISIBLE (-9590 6027);
FORCEPROP 1 LAST OFFPAGE TRUE
J 0
(-9590 6107);
DISPLAY 0.808511 (-9590 6107);
PAINT GREEN (-9590 6107);
DISPLAY INVISIBLE (-9590 6107);
FORCEADD TP_PIONT..1
(-1000 9200);
FORCEPROP 1 LAST $LOCATION TP42
J 0
(-900 9200);
DISPLAY 0.808511 (-900 9200);
PAINT GREEN (-900 9200);
FORCEPROP 0 LAST CDS_LOCATION TP42
J 0
(-900 9250);
DISPLAY 1.021277 (-900 9250);
DISPLAY INVISIBLE (-900 9250);
FORCEPROP 0 LAST $SEC 1
J 0
(-900 9250);
DISPLAY 0.680851 (-900 9250);
PAINT MONO (-900 9250);
DISPLAY INVISIBLE (-900 9250);
FORCEPROP 0 LAST CDS_SEC 1
J 0
(-900 9250);
DISPLAY 1.021277 (-900 9250);
DISPLAY INVISIBLE (-900 9250);
FORCEPROP 0 LASTPIN (-1100 9200) $PN 1
J 2
(-1110 9210);
DISPLAY 0.680851 (-1110 9210);
PAINT MONO (-1110 9210);
FORCEPROP 1 LAST JEDEC_TYPE TP010CT020B030_PTH
J 0
(-1124 9300);
DISPLAY 0.000000 (-1124 9300);
PAINT GREEN (-1124 9300);
DISPLAY INVISIBLE (-1124 9300);
FORCEPROP 1 LAST BOM_IGNORE TRUE
J 0
(-1124 9300);
DISPLAY 0.000000 (-1124 9300);
PAINT GREEN (-1124 9300);
DISPLAY INVISIBLE (-1124 9300);
FORCEPROP 1 LAST CDS_LMAN_SYM_OUTLINE -50,50,50,-50
J 0
(-1000 9200);
DISPLAY 0.468085 (-1000 9200);
PAINT GREEN (-1000 9200);
DISPLAY INVISIBLE (-1000 9200);
FORCEPROP 1 LAST PATH I1665
J 0
(-920 9313);
DISPLAY 0.808511 (-920 9313);
PAINT GREEN (-920 9313);
DISPLAY INVISIBLE (-920 9313);
FORCEPROP 2 LAST CDS_LIB cls
J 0
(-1000 9200);
DISPLAY INVISIBLE (-1000 9200);
FORCEADD VCC..1
(-2000 9350);
FORCEPROP 3 LASTPIN (-1950 9300) SIG_NAME XP12R0V_IN\g
J 0
(-1940 9310);
DISPLAY 0.659574 (-1940 9310);
PAINT MONO (-1940 9310);
DISPLAY INVISIBLE (-1940 9310);
FORCEPROP 0 LAST VOLTAGE 12
J 1
(-1950 9450);
DISPLAY 1.021277 (-1950 9450);
DISPLAY BOTH (-1950 9450);
FORCEPROP 1 LAST HDL_POWER XP12R0V_IN
J 1
(-1950 9400);
DISPLAY 0.808511 (-1950 9400);
PAINT GREEN (-1950 9400);
FORCEPROP 1 LAST BODY_TYPE PLUMBING
J 0
(-2045 9307);
DISPLAY 0.340426 (-2045 9307);
PAINT GREEN (-2045 9307);
DISPLAY INVISIBLE (-2045 9307);
FORCEPROP 1 LAST CDS_LMAN_SYM_OUTLINE -250,250,250,-250
J 0
(-2000 9350);
DISPLAY 0.468085 (-2000 9350);
PAINT GREEN (-2000 9350);
DISPLAY INVISIBLE (-2000 9350);
FORCEPROP 1 LAST PATH I1666
J 0
(-1965 9440);
DISPLAY 0.808511 (-1965 9440);
PAINT GREEN (-1965 9440);
DISPLAY INVISIBLE (-1965 9440);
FORCEPROP 2 LAST CDS_LIB cls
J 0
(-2000 9350);
DISPLAY INVISIBLE (-2000 9350);
FORCEADD TP_PIONT..1
R 2
(-10950 7450);
FORCEPROP 1 LAST $LOCATION TP28
J 2
(-11100 7450);
DISPLAY 0.808511 (-11100 7450);
PAINT GREEN (-11100 7450);
FORCEPROP 0 LAST CDS_LOCATION TP28
J 0
(-11100 7500);
DISPLAY 1.021277 (-11100 7500);
DISPLAY INVISIBLE (-11100 7500);
FORCEPROP 0 LAST $SEC 1
J 0
(-11100 7500);
DISPLAY 0.680851 (-11100 7500);
PAINT MONO (-11100 7500);
DISPLAY INVISIBLE (-11100 7500);
FORCEPROP 0 LAST CDS_SEC 1
J 0
(-11100 7500);
DISPLAY 1.021277 (-11100 7500);
DISPLAY INVISIBLE (-11100 7500);
FORCEPROP 0 LASTPIN (-10850 7450) $PN 1
J 0
(-10840 7460);
DISPLAY 0.680851 (-10840 7460);
PAINT MONO (-10840 7460);
FORCEPROP 1 LAST PATH I1667
J 2
(-11030 7563);
DISPLAY 0.808511 (-11030 7563);
PAINT GREEN (-11030 7563);
DISPLAY INVISIBLE (-11030 7563);
FORCEPROP 1 LAST BOM_IGNORE TRUE
J 2
(-10826 7550);
DISPLAY 0.000000 (-10826 7550);
PAINT GREEN (-10826 7550);
DISPLAY INVISIBLE (-10826 7550);
FORCEPROP 1 LAST JEDEC_TYPE TP010CT020B030_PTH
J 2
(-10826 7550);
DISPLAY 0.000000 (-10826 7550);
PAINT GREEN (-10826 7550);
DISPLAY INVISIBLE (-10826 7550);
FORCEPROP 1 LAST CDS_LMAN_SYM_OUTLINE -50,50,50,-50
J 2
(-10950 7450);
DISPLAY 0.468085 (-10950 7450);
PAINT GREEN (-10950 7450);
DISPLAY INVISIBLE (-10950 7450);
FORCEPROP 2 LAST CDS_LIB cls
J 0
(-10950 7450);
DISPLAY INVISIBLE (-10950 7450);
FORCEADD OFFPAGE_BI..1
R 6
(-9600 7450);
FORCEPROP 2 LAST $XR0 12G5> 
J 0
(-9540 7450);
DISPLAY 0.638298 (-9540 7450);
PAINT MONO (-9540 7450);
FORCEPROP 2 LAST $XR1 23G3< 
J 0
(-9360 7450);
DISPLAY 0.638298 (-9360 7450);
PAINT MONO (-9360 7450);
FORCEPROP 2 LAST CDS_LIB cls
J 0
(-9600 7450);
DISPLAY INVISIBLE (-9600 7450);
FORCEPROP 1 LAST CDS_LMAN_SYM_OUTLINE -50,50,50,-50
J 0
(-9600 7450);
DISPLAY 0.468085 (-9600 7450);
PAINT GREEN (-9600 7450);
DISPLAY INVISIBLE (-9600 7450);
FORCEPROP 1 LAST OFFPAGE TRUE
J 0
(-9590 7357);
DISPLAY 0.808511 (-9590 7357);
PAINT GREEN (-9590 7357);
DISPLAY INVISIBLE (-9590 7357);
FORCEPROP 1 LAST BODY_TYPE COMMENT
J 0
(-9590 7277);
DISPLAY 0.808511 (-9590 7277);
PAINT GREEN (-9590 7277);
DISPLAY INVISIBLE (-9590 7277);
FORCEPROP 2 LAST PATH I1668
J 0
(-9550 7550);
DISPLAY 1.021277 (-9550 7550);
DISPLAY INVISIBLE (-9550 7550);
FORCEADD TP_PIONT..1
R 2
(-10950 6900);
FORCEPROP 1 LAST $LOCATION TP33
J 2
(-11100 6900);
DISPLAY 0.808511 (-11100 6900);
PAINT GREEN (-11100 6900);
FORCEPROP 0 LAST CDS_LOCATION TP33
J 0
(-11100 6950);
DISPLAY 1.021277 (-11100 6950);
DISPLAY INVISIBLE (-11100 6950);
FORCEPROP 0 LAST $SEC 1
J 0
(-11100 6950);
DISPLAY 0.680851 (-11100 6950);
PAINT MONO (-11100 6950);
DISPLAY INVISIBLE (-11100 6950);
FORCEPROP 0 LAST CDS_SEC 1
J 0
(-11100 6950);
DISPLAY 1.021277 (-11100 6950);
DISPLAY INVISIBLE (-11100 6950);
FORCEPROP 0 LASTPIN (-10850 6900) $PN 1
J 0
(-10840 6910);
DISPLAY 0.680851 (-10840 6910);
PAINT MONO (-10840 6910);
FORCEPROP 1 LAST PATH I1669
J 2
(-11030 7013);
DISPLAY 0.808511 (-11030 7013);
PAINT GREEN (-11030 7013);
DISPLAY INVISIBLE (-11030 7013);
FORCEPROP 1 LAST BOM_IGNORE TRUE
J 2
(-10826 7000);
DISPLAY 0.000000 (-10826 7000);
PAINT GREEN (-10826 7000);
DISPLAY INVISIBLE (-10826 7000);
FORCEPROP 1 LAST JEDEC_TYPE TP010CT020B030_PTH
J 2
(-10826 7000);
DISPLAY 0.000000 (-10826 7000);
PAINT GREEN (-10826 7000);
DISPLAY INVISIBLE (-10826 7000);
FORCEPROP 1 LAST CDS_LMAN_SYM_OUTLINE -50,50,50,-50
J 2
(-10950 6900);
DISPLAY 0.468085 (-10950 6900);
PAINT GREEN (-10950 6900);
DISPLAY INVISIBLE (-10950 6900);
FORCEPROP 2 LAST CDS_LIB cls
J 0
(-10950 6900);
DISPLAY INVISIBLE (-10950 6900);
FORCEADD OFFPAGE_BI..1
R 6
(-9600 6900);
FORCEPROP 2 LAST $XR1 23J3< 
J 0
(-9360 6900);
DISPLAY 0.638298 (-9360 6900);
PAINT MONO (-9360 6900);
FORCEPROP 2 LAST $XR0 12G5> 
J 0
(-9540 6900);
DISPLAY 0.638298 (-9540 6900);
PAINT MONO (-9540 6900);
FORCEPROP 2 LAST PATH I1670
J 0
(-9550 7000);
DISPLAY 1.021277 (-9550 7000);
DISPLAY INVISIBLE (-9550 7000);
FORCEPROP 1 LAST BODY_TYPE COMMENT
J 0
(-9590 6727);
DISPLAY 0.808511 (-9590 6727);
PAINT GREEN (-9590 6727);
DISPLAY INVISIBLE (-9590 6727);
FORCEPROP 1 LAST OFFPAGE TRUE
J 0
(-9590 6807);
DISPLAY 0.808511 (-9590 6807);
PAINT GREEN (-9590 6807);
DISPLAY INVISIBLE (-9590 6807);
FORCEPROP 1 LAST CDS_LMAN_SYM_OUTLINE -50,50,50,-50
J 0
(-9600 6900);
DISPLAY 0.468085 (-9600 6900);
PAINT GREEN (-9600 6900);
DISPLAY INVISIBLE (-9600 6900);
FORCEPROP 2 LAST CDS_LIB cls
J 0
(-9600 6900);
DISPLAY INVISIBLE (-9600 6900);
FORCEADD OFFPAGE_BI..1
R 6
(-9600 7350);
FORCEPROP 2 LAST $XR0 12H5> 
J 0
(-9540 7350);
DISPLAY 0.638298 (-9540 7350);
PAINT MONO (-9540 7350);
FORCEPROP 2 LAST $XR1 23K3< 
J 0
(-9360 7350);
DISPLAY 0.638298 (-9360 7350);
PAINT MONO (-9360 7350);
FORCEPROP 2 LAST PATH I1671
J 0
(-9550 7450);
DISPLAY 1.021277 (-9550 7450);
DISPLAY INVISIBLE (-9550 7450);
FORCEPROP 2 LAST CDS_LIB cls
J 0
(-9600 7350);
DISPLAY INVISIBLE (-9600 7350);
FORCEPROP 1 LAST CDS_LMAN_SYM_OUTLINE -50,50,50,-50
J 0
(-9600 7350);
DISPLAY 0.468085 (-9600 7350);
PAINT GREEN (-9600 7350);
DISPLAY INVISIBLE (-9600 7350);
FORCEPROP 1 LAST OFFPAGE TRUE
J 0
(-9590 7257);
DISPLAY 0.808511 (-9590 7257);
PAINT GREEN (-9590 7257);
DISPLAY INVISIBLE (-9590 7257);
FORCEPROP 1 LAST BODY_TYPE COMMENT
J 0
(-9590 7177);
DISPLAY 0.808511 (-9590 7177);
PAINT GREEN (-9590 7177);
DISPLAY INVISIBLE (-9590 7177);
FORCEADD TP_PIONT..1
R 2
(-10950 7350);
FORCEPROP 1 LAST $LOCATION TP29
J 2
(-11100 7350);
DISPLAY 0.808511 (-11100 7350);
PAINT GREEN (-11100 7350);
FORCEPROP 0 LAST CDS_LOCATION TP29
J 0
(-11100 7400);
DISPLAY 1.021277 (-11100 7400);
DISPLAY INVISIBLE (-11100 7400);
FORCEPROP 0 LAST $SEC 1
J 0
(-11100 7400);
DISPLAY 0.680851 (-11100 7400);
PAINT MONO (-11100 7400);
DISPLAY INVISIBLE (-11100 7400);
FORCEPROP 0 LAST CDS_SEC 1
J 0
(-11100 7400);
DISPLAY 1.021277 (-11100 7400);
DISPLAY INVISIBLE (-11100 7400);
FORCEPROP 0 LASTPIN (-10850 7350) $PN 1
J 0
(-10840 7360);
DISPLAY 0.680851 (-10840 7360);
PAINT MONO (-10840 7360);
FORCEPROP 1 LAST BOM_IGNORE TRUE
J 2
(-10826 7450);
DISPLAY 0.000000 (-10826 7450);
PAINT GREEN (-10826 7450);
DISPLAY INVISIBLE (-10826 7450);
FORCEPROP 1 LAST JEDEC_TYPE TP010CT020B030_PTH
J 2
(-10826 7450);
DISPLAY 0.000000 (-10826 7450);
PAINT GREEN (-10826 7450);
DISPLAY INVISIBLE (-10826 7450);
FORCEPROP 1 LAST CDS_LMAN_SYM_OUTLINE -50,50,50,-50
J 2
(-10950 7350);
DISPLAY 0.468085 (-10950 7350);
PAINT GREEN (-10950 7350);
DISPLAY INVISIBLE (-10950 7350);
FORCEPROP 2 LAST CDS_LIB cls
J 0
(-10950 7350);
DISPLAY INVISIBLE (-10950 7350);
FORCEPROP 1 LAST PATH I1672
J 2
(-11030 7463);
DISPLAY 0.808511 (-11030 7463);
PAINT GREEN (-11030 7463);
DISPLAY INVISIBLE (-11030 7463);
FORCEADD TP_PIONT..1
R 2
(-10950 6800);
FORCEPROP 1 LAST $LOCATION TP34
J 2
(-11100 6800);
DISPLAY 0.808511 (-11100 6800);
PAINT GREEN (-11100 6800);
FORCEPROP 0 LAST CDS_LOCATION TP34
J 0
(-11100 6850);
DISPLAY 1.021277 (-11100 6850);
DISPLAY INVISIBLE (-11100 6850);
FORCEPROP 0 LAST $SEC 1
J 0
(-11100 6850);
DISPLAY 0.680851 (-11100 6850);
PAINT MONO (-11100 6850);
DISPLAY INVISIBLE (-11100 6850);
FORCEPROP 0 LAST CDS_SEC 1
J 0
(-11100 6850);
DISPLAY 1.021277 (-11100 6850);
DISPLAY INVISIBLE (-11100 6850);
FORCEPROP 0 LASTPIN (-10850 6800) $PN 1
J 0
(-10840 6810);
DISPLAY 0.680851 (-10840 6810);
PAINT MONO (-10840 6810);
FORCEPROP 2 LAST CDS_LIB cls
J 0
(-10950 6800);
DISPLAY INVISIBLE (-10950 6800);
FORCEPROP 1 LAST CDS_LMAN_SYM_OUTLINE -50,50,50,-50
J 2
(-10950 6800);
DISPLAY 0.468085 (-10950 6800);
PAINT GREEN (-10950 6800);
DISPLAY INVISIBLE (-10950 6800);
FORCEPROP 1 LAST JEDEC_TYPE TP010CT020B030_PTH
J 2
(-10826 6900);
DISPLAY 0.000000 (-10826 6900);
PAINT GREEN (-10826 6900);
DISPLAY INVISIBLE (-10826 6900);
FORCEPROP 1 LAST BOM_IGNORE TRUE
J 2
(-10826 6900);
DISPLAY 0.000000 (-10826 6900);
PAINT GREEN (-10826 6900);
DISPLAY INVISIBLE (-10826 6900);
FORCEPROP 1 LAST PATH I1673
J 2
(-11030 6913);
DISPLAY 0.808511 (-11030 6913);
PAINT GREEN (-11030 6913);
DISPLAY INVISIBLE (-11030 6913);
FORCEADD OFFPAGE_BI..1
R 6
(-9600 6800);
FORCEPROP 2 LAST $XR1 23C3< 
J 0
(-9360 6800);
DISPLAY 0.638298 (-9360 6800);
PAINT MONO (-9360 6800);
FORCEPROP 2 LAST $XR0 12D5> 
J 0
(-9540 6800);
DISPLAY 0.638298 (-9540 6800);
PAINT MONO (-9540 6800);
FORCEPROP 1 LAST BODY_TYPE COMMENT
J 0
(-9590 6627);
DISPLAY 0.808511 (-9590 6627);
PAINT GREEN (-9590 6627);
DISPLAY INVISIBLE (-9590 6627);
FORCEPROP 1 LAST OFFPAGE TRUE
J 0
(-9590 6707);
DISPLAY 0.808511 (-9590 6707);
PAINT GREEN (-9590 6707);
DISPLAY INVISIBLE (-9590 6707);
FORCEPROP 1 LAST CDS_LMAN_SYM_OUTLINE -50,50,50,-50
J 0
(-9600 6800);
DISPLAY 0.468085 (-9600 6800);
PAINT GREEN (-9600 6800);
DISPLAY INVISIBLE (-9600 6800);
FORCEPROP 2 LAST CDS_LIB cls
J 0
(-9600 6800);
DISPLAY INVISIBLE (-9600 6800);
FORCEPROP 2 LAST PATH I1674
J 0
(-9550 6900);
DISPLAY 1.021277 (-9550 6900);
DISPLAY INVISIBLE (-9550 6900);
FORCEADD TP_PIONT..1
R 2
(-10950 6700);
FORCEPROP 1 LAST $LOCATION TP35
J 2
(-11100 6700);
DISPLAY 0.808511 (-11100 6700);
PAINT GREEN (-11100 6700);
FORCEPROP 0 LAST CDS_LOCATION TP35
J 0
(-11100 6750);
DISPLAY 1.021277 (-11100 6750);
DISPLAY INVISIBLE (-11100 6750);
FORCEPROP 0 LAST $SEC 1
J 0
(-11100 6750);
DISPLAY 0.680851 (-11100 6750);
PAINT MONO (-11100 6750);
DISPLAY INVISIBLE (-11100 6750);
FORCEPROP 0 LAST CDS_SEC 1
J 0
(-11100 6750);
DISPLAY 1.021277 (-11100 6750);
DISPLAY INVISIBLE (-11100 6750);
FORCEPROP 0 LASTPIN (-10850 6700) $PN 1
J 0
(-10840 6710);
DISPLAY 0.680851 (-10840 6710);
PAINT MONO (-10840 6710);
FORCEPROP 2 LAST CDS_LIB cls
J 0
(-10950 6700);
DISPLAY INVISIBLE (-10950 6700);
FORCEPROP 1 LAST CDS_LMAN_SYM_OUTLINE -50,50,50,-50
J 2
(-10950 6700);
DISPLAY 0.468085 (-10950 6700);
PAINT GREEN (-10950 6700);
DISPLAY INVISIBLE (-10950 6700);
FORCEPROP 1 LAST JEDEC_TYPE TP010CT020B030_PTH
J 2
(-10826 6800);
DISPLAY 0.000000 (-10826 6800);
PAINT GREEN (-10826 6800);
DISPLAY INVISIBLE (-10826 6800);
FORCEPROP 1 LAST BOM_IGNORE TRUE
J 2
(-10826 6800);
DISPLAY 0.000000 (-10826 6800);
PAINT GREEN (-10826 6800);
DISPLAY INVISIBLE (-10826 6800);
FORCEPROP 1 LAST PATH I1675
J 2
(-11030 6813);
DISPLAY 0.808511 (-11030 6813);
PAINT GREEN (-11030 6813);
DISPLAY INVISIBLE (-11030 6813);
FORCEADD OFFPAGE_BI..1
R 6
(-9600 7250);
FORCEPROP 2 LAST $XR1 23C3< 
J 0
(-9350 7250);
DISPLAY 0.638298 (-9350 7250);
PAINT MONO (-9350 7250);
FORCEPROP 2 LAST $XR0 12E5> 
J 0
(-9540 7250);
DISPLAY 0.638298 (-9540 7250);
PAINT MONO (-9540 7250);
FORCEPROP 1 LAST BODY_TYPE COMMENT
J 0
(-9590 7077);
DISPLAY 0.808511 (-9590 7077);
PAINT GREEN (-9590 7077);
DISPLAY INVISIBLE (-9590 7077);
FORCEPROP 1 LAST OFFPAGE TRUE
J 0
(-9590 7157);
DISPLAY 0.808511 (-9590 7157);
PAINT GREEN (-9590 7157);
DISPLAY INVISIBLE (-9590 7157);
FORCEPROP 1 LAST CDS_LMAN_SYM_OUTLINE -50,50,50,-50
J 0
(-9600 7250);
DISPLAY 0.468085 (-9600 7250);
PAINT GREEN (-9600 7250);
DISPLAY INVISIBLE (-9600 7250);
FORCEPROP 2 LAST CDS_LIB cls
J 0
(-9600 7250);
DISPLAY INVISIBLE (-9600 7250);
FORCEPROP 2 LAST PATH I1676
J 0
(-9550 7350);
DISPLAY 1.021277 (-9550 7350);
DISPLAY INVISIBLE (-9550 7350);
FORCEADD OFFPAGE_BI..1
R 6
(-9600 6700);
FORCEPROP 2 LAST $XR0 12D5> 
J 0
(-9540 6700);
DISPLAY 0.638298 (-9540 6700);
PAINT MONO (-9540 6700);
FORCEPROP 2 LAST $XR1 23E3< 
J 0
(-9360 6700);
DISPLAY 0.638298 (-9360 6700);
PAINT MONO (-9360 6700);
FORCEPROP 1 LAST BODY_TYPE COMMENT
J 0
(-9590 6527);
DISPLAY 0.808511 (-9590 6527);
PAINT GREEN (-9590 6527);
DISPLAY INVISIBLE (-9590 6527);
FORCEPROP 1 LAST OFFPAGE TRUE
J 0
(-9590 6607);
DISPLAY 0.808511 (-9590 6607);
PAINT GREEN (-9590 6607);
DISPLAY INVISIBLE (-9590 6607);
FORCEPROP 1 LAST CDS_LMAN_SYM_OUTLINE -50,50,50,-50
J 0
(-9600 6700);
DISPLAY 0.468085 (-9600 6700);
PAINT GREEN (-9600 6700);
DISPLAY INVISIBLE (-9600 6700);
FORCEPROP 2 LAST CDS_LIB cls
J 0
(-9600 6700);
DISPLAY INVISIBLE (-9600 6700);
FORCEPROP 2 LAST PATH I1677
J 0
(-9550 6800);
DISPLAY 1.021277 (-9550 6800);
DISPLAY INVISIBLE (-9550 6800);
FORCEADD TP_PIONT..1
R 2
(-10950 7250);
FORCEPROP 1 LAST $LOCATION TP30
J 2
(-11100 7250);
DISPLAY 0.808511 (-11100 7250);
PAINT GREEN (-11100 7250);
FORCEPROP 0 LAST CDS_LOCATION TP30
J 0
(-11100 7300);
DISPLAY 1.021277 (-11100 7300);
DISPLAY INVISIBLE (-11100 7300);
FORCEPROP 0 LAST $SEC 1
J 0
(-11100 7300);
DISPLAY 0.680851 (-11100 7300);
PAINT MONO (-11100 7300);
DISPLAY INVISIBLE (-11100 7300);
FORCEPROP 0 LAST CDS_SEC 1
J 0
(-11100 7300);
DISPLAY 1.021277 (-11100 7300);
DISPLAY INVISIBLE (-11100 7300);
FORCEPROP 0 LASTPIN (-10850 7250) $PN 1
J 0
(-10840 7260);
DISPLAY 0.680851 (-10840 7260);
PAINT MONO (-10840 7260);
FORCEPROP 2 LAST CDS_LIB cls
J 0
(-10950 7250);
DISPLAY INVISIBLE (-10950 7250);
FORCEPROP 1 LAST CDS_LMAN_SYM_OUTLINE -50,50,50,-50
J 2
(-10950 7250);
DISPLAY 0.468085 (-10950 7250);
PAINT GREEN (-10950 7250);
DISPLAY INVISIBLE (-10950 7250);
FORCEPROP 1 LAST JEDEC_TYPE TP010CT020B030_PTH
J 2
(-10826 7350);
DISPLAY 0.000000 (-10826 7350);
PAINT GREEN (-10826 7350);
DISPLAY INVISIBLE (-10826 7350);
FORCEPROP 1 LAST BOM_IGNORE TRUE
J 2
(-10826 7350);
DISPLAY 0.000000 (-10826 7350);
PAINT GREEN (-10826 7350);
DISPLAY INVISIBLE (-10826 7350);
FORCEPROP 1 LAST PATH I1678
J 2
(-11030 7363);
DISPLAY 0.808511 (-11030 7363);
PAINT GREEN (-11030 7363);
DISPLAY INVISIBLE (-11030 7363);
FORCEADD TP_PIONT..1
R 2
(-10950 7150);
FORCEPROP 1 LAST $LOCATION TP31
J 2
(-11100 7150);
DISPLAY 0.808511 (-11100 7150);
PAINT GREEN (-11100 7150);
FORCEPROP 0 LAST CDS_LOCATION TP31
J 0
(-11100 7200);
DISPLAY 1.021277 (-11100 7200);
DISPLAY INVISIBLE (-11100 7200);
FORCEPROP 0 LAST $SEC 1
J 0
(-11100 7200);
DISPLAY 0.680851 (-11100 7200);
PAINT MONO (-11100 7200);
DISPLAY INVISIBLE (-11100 7200);
FORCEPROP 0 LAST CDS_SEC 1
J 0
(-11100 7200);
DISPLAY 1.021277 (-11100 7200);
DISPLAY INVISIBLE (-11100 7200);
FORCEPROP 0 LASTPIN (-10850 7150) $PN 1
J 0
(-10840 7160);
DISPLAY 0.680851 (-10840 7160);
PAINT MONO (-10840 7160);
FORCEPROP 1 LAST PATH I1679
J 2
(-11030 7263);
DISPLAY 0.808511 (-11030 7263);
PAINT GREEN (-11030 7263);
DISPLAY INVISIBLE (-11030 7263);
FORCEPROP 1 LAST BOM_IGNORE TRUE
J 2
(-10826 7250);
DISPLAY 0.000000 (-10826 7250);
PAINT GREEN (-10826 7250);
DISPLAY INVISIBLE (-10826 7250);
FORCEPROP 1 LAST JEDEC_TYPE TP010CT020B030_PTH
J 2
(-10826 7250);
DISPLAY 0.000000 (-10826 7250);
PAINT GREEN (-10826 7250);
DISPLAY INVISIBLE (-10826 7250);
FORCEPROP 1 LAST CDS_LMAN_SYM_OUTLINE -50,50,50,-50
J 2
(-10950 7150);
DISPLAY 0.468085 (-10950 7150);
PAINT GREEN (-10950 7150);
DISPLAY INVISIBLE (-10950 7150);
FORCEPROP 2 LAST CDS_LIB cls
J 0
(-10950 7150);
DISPLAY INVISIBLE (-10950 7150);
FORCEADD OFFPAGE_BI..1
R 6
(-9600 7150);
FORCEPROP 2 LAST $XR0 12D5> 
J 0
(-9540 7150);
DISPLAY 0.638298 (-9540 7150);
PAINT MONO (-9540 7150);
FORCEPROP 2 LAST $XR1 23E3< 
J 0
(-9360 7150);
DISPLAY 0.638298 (-9360 7150);
PAINT MONO (-9360 7150);
FORCEPROP 2 LAST PATH I1680
J 0
(-9550 7250);
DISPLAY 1.021277 (-9550 7250);
DISPLAY INVISIBLE (-9550 7250);
FORCEPROP 2 LAST CDS_LIB cls
J 0
(-9600 7150);
DISPLAY INVISIBLE (-9600 7150);
FORCEPROP 1 LAST CDS_LMAN_SYM_OUTLINE -50,50,50,-50
J 0
(-9600 7150);
DISPLAY 0.468085 (-9600 7150);
PAINT GREEN (-9600 7150);
DISPLAY INVISIBLE (-9600 7150);
FORCEPROP 1 LAST OFFPAGE TRUE
J 0
(-9590 7057);
DISPLAY 0.808511 (-9590 7057);
PAINT GREEN (-9590 7057);
DISPLAY INVISIBLE (-9590 7057);
FORCEPROP 1 LAST BODY_TYPE COMMENT
J 0
(-9590 6977);
DISPLAY 0.808511 (-9590 6977);
PAINT GREEN (-9590 6977);
DISPLAY INVISIBLE (-9590 6977);
FORCEADD OFFPAGE_BI..1
R 6
(-9600 6300);
FORCEPROP 2 LAST $XR0 27F11> 
J 0
(-9540 6300);
DISPLAY 0.638298 (-9540 6300);
PAINT MONO (-9540 6300);
FORCEPROP 2 LAST CDS_LIB cls
J 0
(-9600 6300);
DISPLAY INVISIBLE (-9600 6300);
FORCEPROP 1 LAST CDS_LMAN_SYM_OUTLINE -50,50,50,-50
J 0
(-9600 6300);
DISPLAY 0.468085 (-9600 6300);
PAINT GREEN (-9600 6300);
DISPLAY INVISIBLE (-9600 6300);
FORCEPROP 1 LAST BODY_TYPE COMMENT
J 0
(-9590 6127);
DISPLAY 0.808511 (-9590 6127);
PAINT GREEN (-9590 6127);
DISPLAY INVISIBLE (-9590 6127);
FORCEPROP 1 LAST OFFPAGE TRUE
J 0
(-9590 6207);
DISPLAY 0.808511 (-9590 6207);
PAINT GREEN (-9590 6207);
DISPLAY INVISIBLE (-9590 6207);
FORCEPROP 2 LAST PATH I1681
J 0
(-9500 6350);
DISPLAY 1.021277 (-9500 6350);
DISPLAY INVISIBLE (-9500 6350);
FORCEADD TP_PIONT..1
R 2
(-10950 6300);
FORCEPROP 1 LAST $LOCATION TP37
J 2
(-11100 6300);
DISPLAY 0.808511 (-11100 6300);
PAINT GREEN (-11100 6300);
FORCEPROP 0 LAST CDS_LOCATION TP37
J 0
(-11100 6350);
DISPLAY 1.021277 (-11100 6350);
DISPLAY INVISIBLE (-11100 6350);
FORCEPROP 0 LAST $SEC 1
J 0
(-11100 6350);
DISPLAY 0.680851 (-11100 6350);
PAINT MONO (-11100 6350);
DISPLAY INVISIBLE (-11100 6350);
FORCEPROP 0 LAST CDS_SEC 1
J 0
(-11100 6350);
DISPLAY 1.021277 (-11100 6350);
DISPLAY INVISIBLE (-11100 6350);
FORCEPROP 0 LASTPIN (-10850 6300) $PN 1
J 0
(-10840 6310);
DISPLAY 0.680851 (-10840 6310);
PAINT MONO (-10840 6310);
FORCEPROP 2 LAST CDS_LIB cls
J 0
(-10950 6300);
DISPLAY INVISIBLE (-10950 6300);
FORCEPROP 1 LAST CDS_LMAN_SYM_OUTLINE -50,50,50,-50
J 2
(-10950 6300);
DISPLAY 0.468085 (-10950 6300);
PAINT GREEN (-10950 6300);
DISPLAY INVISIBLE (-10950 6300);
FORCEPROP 1 LAST JEDEC_TYPE TP010CT020B030_PTH
J 2
(-10826 6400);
DISPLAY 0.000000 (-10826 6400);
PAINT GREEN (-10826 6400);
DISPLAY INVISIBLE (-10826 6400);
FORCEPROP 1 LAST BOM_IGNORE TRUE
J 2
(-10826 6400);
DISPLAY 0.000000 (-10826 6400);
PAINT GREEN (-10826 6400);
DISPLAY INVISIBLE (-10826 6400);
FORCEPROP 1 LAST PATH I1682
J 2
(-11030 6413);
DISPLAY 0.808511 (-11030 6413);
PAINT GREEN (-11030 6413);
DISPLAY INVISIBLE (-11030 6413);
FORCEADD TP_PIONT..1
R 2
(-8250 9300);
FORCEPROP 1 LAST $LOCATION TP46
J 2
(-8350 9300);
DISPLAY 0.808511 (-8350 9300);
PAINT GREEN (-8350 9300);
FORCEPROP 0 LAST CDS_LOCATION TP46
J 0
(-8350 9350);
DISPLAY 1.021277 (-8350 9350);
DISPLAY INVISIBLE (-8350 9350);
FORCEPROP 0 LAST $SEC 1
J 0
(-8350 9350);
DISPLAY 0.680851 (-8350 9350);
PAINT MONO (-8350 9350);
DISPLAY INVISIBLE (-8350 9350);
FORCEPROP 0 LAST CDS_SEC 1
J 0
(-8350 9350);
DISPLAY 1.021277 (-8350 9350);
DISPLAY INVISIBLE (-8350 9350);
FORCEPROP 0 LASTPIN (-8150 9300) $PN 1
J 0
(-8140 9310);
DISPLAY 0.680851 (-8140 9310);
PAINT MONO (-8140 9310);
FORCEPROP 1 LAST CDS_LMAN_SYM_OUTLINE -50,50,50,-50
J 2
(-8250 9300);
DISPLAY 0.468085 (-8250 9300);
PAINT GREEN (-8250 9300);
DISPLAY INVISIBLE (-8250 9300);
FORCEPROP 2 LAST CDS_LIB cls
J 0
(-8250 9300);
DISPLAY INVISIBLE (-8250 9300);
FORCEPROP 1 LAST PATH I1684
J 2
(-8330 9413);
DISPLAY 0.808511 (-8330 9413);
PAINT GREEN (-8330 9413);
DISPLAY INVISIBLE (-8330 9413);
FORCEPROP 1 LAST JEDEC_TYPE TP010CT020B030_PTH
J 2
(-8126 9400);
DISPLAY 0.000000 (-8126 9400);
PAINT GREEN (-8126 9400);
DISPLAY INVISIBLE (-8126 9400);
FORCEPROP 1 LAST BOM_IGNORE TRUE
J 2
(-8126 9400);
DISPLAY 0.000000 (-8126 9400);
PAINT GREEN (-8126 9400);
DISPLAY INVISIBLE (-8126 9400);
FORCEADD OFFPAGE_BI..1
R 6
(-6900 9500);
FORCEPROP 2 LAST $XR1 26D8< 
J 0
(-6840 9500);
DISPLAY 0.638298 (-6840 9500);
PAINT MONO (-6840 9500);
FORCEPROP 2 LAST $XR0 10E12< 
J 0
(-6650 9500);
DISPLAY 0.638298 (-6650 9500);
PAINT MONO (-6650 9500);
FORCEPROP 2 LAST CDS_LIB cls
J 0
(-6900 9500);
DISPLAY INVISIBLE (-6900 9500);
FORCEPROP 2 LAST PATH I1685
J 0
(-6850 9600);
DISPLAY 1.021277 (-6850 9600);
DISPLAY INVISIBLE (-6850 9600);
FORCEPROP 1 LAST CDS_LMAN_SYM_OUTLINE -50,50,50,-50
J 0
(-6900 9500);
DISPLAY 0.468085 (-6900 9500);
PAINT GREEN (-6900 9500);
DISPLAY INVISIBLE (-6900 9500);
FORCEPROP 1 LAST OFFPAGE TRUE
J 0
(-6890 9407);
DISPLAY 0.808511 (-6890 9407);
PAINT GREEN (-6890 9407);
DISPLAY INVISIBLE (-6890 9407);
FORCEPROP 1 LAST BODY_TYPE COMMENT
J 0
(-6890 9327);
DISPLAY 0.808511 (-6890 9327);
PAINT GREEN (-6890 9327);
DISPLAY INVISIBLE (-6890 9327);
FORCEADD OFFPAGE_BI..1
R 6
(-6900 9400);
FORCEPROP 2 LAST $XR0 9E15> 
J 0
(-6840 9400);
DISPLAY 0.638298 (-6840 9400);
PAINT MONO (-6840 9400);
FORCEPROP 2 LAST $XR1 10F5< 
J 0
(-6660 9400);
DISPLAY 0.638298 (-6660 9400);
PAINT MONO (-6660 9400);
FORCEPROP 2 LAST CDS_LIB cls
J 0
(-6900 9400);
DISPLAY INVISIBLE (-6900 9400);
FORCEPROP 2 LAST PATH I1686
J 0
(-6850 9500);
DISPLAY 1.021277 (-6850 9500);
DISPLAY INVISIBLE (-6850 9500);
FORCEPROP 1 LAST CDS_LMAN_SYM_OUTLINE -50,50,50,-50
J 0
(-6900 9400);
DISPLAY 0.468085 (-6900 9400);
PAINT GREEN (-6900 9400);
DISPLAY INVISIBLE (-6900 9400);
FORCEPROP 1 LAST OFFPAGE TRUE
J 0
(-6890 9307);
DISPLAY 0.808511 (-6890 9307);
PAINT GREEN (-6890 9307);
DISPLAY INVISIBLE (-6890 9307);
FORCEPROP 1 LAST BODY_TYPE COMMENT
J 0
(-6890 9227);
DISPLAY 0.808511 (-6890 9227);
PAINT GREEN (-6890 9227);
DISPLAY INVISIBLE (-6890 9227);
FORCEADD OFFPAGE_BI..1
R 6
(-6900 9300);
FORCEPROP 2 LAST $XR2 31K11> 
J 0
(-6450 9300);
DISPLAY 0.638298 (-6450 9300);
PAINT MONO (-6450 9300);
FORCEPROP 2 LAST $XR3 32H7> 
J 0
(-6240 9300);
DISPLAY 0.638298 (-6240 9300);
PAINT MONO (-6240 9300);
FORCEPROP 2 LAST $XR4 10F12< 
J 0
(-6060 9300);
DISPLAY 0.638298 (-6060 9300);
PAINT MONO (-6060 9300);
FORCEPROP 2 LAST $XR1 31D7> 
J 0
(-6630 9300);
DISPLAY 0.638298 (-6630 9300);
PAINT MONO (-6630 9300);
FORCEPROP 2 LAST $XR0 24F15> 
J 0
(-6840 9300);
DISPLAY 0.638298 (-6840 9300);
PAINT MONO (-6840 9300);
FORCEPROP 1 LAST CDS_LMAN_SYM_OUTLINE -50,50,50,-50
J 0
(-6900 9300);
DISPLAY 0.468085 (-6900 9300);
PAINT GREEN (-6900 9300);
DISPLAY INVISIBLE (-6900 9300);
FORCEPROP 2 LAST CDS_LIB cls
J 0
(-6900 9300);
DISPLAY INVISIBLE (-6900 9300);
FORCEPROP 2 LAST PATH I1687
J 0
(-6850 9400);
DISPLAY 1.021277 (-6850 9400);
DISPLAY INVISIBLE (-6850 9400);
FORCEPROP 1 LAST BODY_TYPE COMMENT
J 0
(-6890 9127);
DISPLAY 0.808511 (-6890 9127);
PAINT GREEN (-6890 9127);
DISPLAY INVISIBLE (-6890 9127);
FORCEPROP 1 LAST OFFPAGE TRUE
J 0
(-6890 9207);
DISPLAY 0.808511 (-6890 9207);
PAINT GREEN (-6890 9207);
DISPLAY INVISIBLE (-6890 9207);
FORCEADD OFFPAGE_BI..1
R 6
(-9600 6500);
FORCEPROP 2 LAST $XR0 27F7< 
J 0
(-9540 6500);
DISPLAY 0.638298 (-9540 6500);
PAINT MONO (-9540 6500);
FORCEPROP 2 LAST CDS_LIB cls
J 0
(-9600 6500);
DISPLAY INVISIBLE (-9600 6500);
FORCEPROP 2 LAST PATH I1688
J 0
(-9550 6600);
DISPLAY 1.021277 (-9550 6600);
DISPLAY INVISIBLE (-9550 6600);
FORCEPROP 1 LAST CDS_LMAN_SYM_OUTLINE -50,50,50,-50
J 0
(-9600 6500);
DISPLAY 0.468085 (-9600 6500);
PAINT GREEN (-9600 6500);
DISPLAY INVISIBLE (-9600 6500);
FORCEPROP 1 LAST OFFPAGE TRUE
J 0
(-9590 6407);
DISPLAY 0.808511 (-9590 6407);
PAINT GREEN (-9590 6407);
DISPLAY INVISIBLE (-9590 6407);
FORCEPROP 1 LAST BODY_TYPE COMMENT
J 0
(-9590 6327);
DISPLAY 0.808511 (-9590 6327);
PAINT GREEN (-9590 6327);
DISPLAY INVISIBLE (-9590 6327);
FORCEADD TP_PIONT..1
R 2
(-8250 9500);
FORCEPROP 1 LAST $LOCATION TP44
J 2
(-8350 9500);
DISPLAY 0.808511 (-8350 9500);
PAINT GREEN (-8350 9500);
FORCEPROP 0 LAST CDS_LOCATION TP44
J 0
(-8350 9550);
DISPLAY 1.021277 (-8350 9550);
DISPLAY INVISIBLE (-8350 9550);
FORCEPROP 0 LAST $SEC 1
J 0
(-8350 9550);
DISPLAY 0.680851 (-8350 9550);
PAINT MONO (-8350 9550);
DISPLAY INVISIBLE (-8350 9550);
FORCEPROP 0 LAST CDS_SEC 1
J 0
(-8350 9550);
DISPLAY 1.021277 (-8350 9550);
DISPLAY INVISIBLE (-8350 9550);
FORCEPROP 0 LASTPIN (-8150 9500) $PN 1
J 0
(-8140 9510);
DISPLAY 0.680851 (-8140 9510);
PAINT MONO (-8140 9510);
FORCEPROP 2 LAST CDS_LIB cls
J 0
(-8250 9500);
DISPLAY INVISIBLE (-8250 9500);
FORCEPROP 1 LAST PATH I1689
J 2
(-8330 9613);
DISPLAY 0.808511 (-8330 9613);
PAINT GREEN (-8330 9613);
DISPLAY INVISIBLE (-8330 9613);
FORCEPROP 1 LAST CDS_LMAN_SYM_OUTLINE -50,50,50,-50
J 2
(-8250 9500);
DISPLAY 0.468085 (-8250 9500);
PAINT GREEN (-8250 9500);
DISPLAY INVISIBLE (-8250 9500);
FORCEPROP 1 LAST BOM_IGNORE TRUE
J 2
(-8126 9600);
DISPLAY 0.000000 (-8126 9600);
PAINT GREEN (-8126 9600);
DISPLAY INVISIBLE (-8126 9600);
FORCEPROP 1 LAST JEDEC_TYPE TP010CT020B030_PTH
J 2
(-8126 9600);
DISPLAY 0.000000 (-8126 9600);
PAINT GREEN (-8126 9600);
DISPLAY INVISIBLE (-8126 9600);
FORCEADD TP_PIONT..1
R 2
(-8250 9400);
FORCEPROP 1 LAST $LOCATION TP45
J 2
(-8350 9400);
DISPLAY 0.808511 (-8350 9400);
PAINT GREEN (-8350 9400);
FORCEPROP 0 LAST CDS_LOCATION TP45
J 0
(-8350 9450);
DISPLAY 1.021277 (-8350 9450);
DISPLAY INVISIBLE (-8350 9450);
FORCEPROP 0 LAST $SEC 1
J 0
(-8350 9450);
DISPLAY 0.680851 (-8350 9450);
PAINT MONO (-8350 9450);
DISPLAY INVISIBLE (-8350 9450);
FORCEPROP 0 LAST CDS_SEC 1
J 0
(-8350 9450);
DISPLAY 1.021277 (-8350 9450);
DISPLAY INVISIBLE (-8350 9450);
FORCEPROP 0 LASTPIN (-8150 9400) $PN 1
J 0
(-8140 9410);
DISPLAY 0.680851 (-8140 9410);
PAINT MONO (-8140 9410);
FORCEPROP 2 LAST CDS_LIB cls
J 0
(-8250 9400);
DISPLAY INVISIBLE (-8250 9400);
FORCEPROP 1 LAST PATH I1690
J 2
(-8330 9513);
DISPLAY 0.808511 (-8330 9513);
PAINT GREEN (-8330 9513);
DISPLAY INVISIBLE (-8330 9513);
FORCEPROP 1 LAST CDS_LMAN_SYM_OUTLINE -50,50,50,-50
J 2
(-8250 9400);
DISPLAY 0.468085 (-8250 9400);
PAINT GREEN (-8250 9400);
DISPLAY INVISIBLE (-8250 9400);
FORCEPROP 1 LAST BOM_IGNORE TRUE
J 2
(-8126 9500);
DISPLAY 0.000000 (-8126 9500);
PAINT GREEN (-8126 9500);
DISPLAY INVISIBLE (-8126 9500);
FORCEPROP 1 LAST JEDEC_TYPE TP010CT020B030_PTH
J 2
(-8126 9500);
DISPLAY 0.000000 (-8126 9500);
PAINT GREEN (-8126 9500);
DISPLAY INVISIBLE (-8126 9500);
FORCEADD TP_PIONT..1
R 2
(-10950 6500);
FORCEPROP 1 LAST $LOCATION TP43
J 2
(-11100 6500);
DISPLAY 0.808511 (-11100 6500);
PAINT GREEN (-11100 6500);
FORCEPROP 0 LAST CDS_LOCATION TP43
J 0
(-11100 6550);
DISPLAY 1.021277 (-11100 6550);
DISPLAY INVISIBLE (-11100 6550);
FORCEPROP 0 LAST $SEC 1
J 0
(-11100 6550);
DISPLAY 0.680851 (-11100 6550);
PAINT MONO (-11100 6550);
DISPLAY INVISIBLE (-11100 6550);
FORCEPROP 0 LAST CDS_SEC 1
J 0
(-11100 6550);
DISPLAY 1.021277 (-11100 6550);
DISPLAY INVISIBLE (-11100 6550);
FORCEPROP 0 LASTPIN (-10850 6500) $PN 1
J 0
(-10840 6510);
DISPLAY 0.680851 (-10840 6510);
PAINT MONO (-10840 6510);
FORCEPROP 2 LAST CDS_LIB cls
J 0
(-10950 6500);
DISPLAY INVISIBLE (-10950 6500);
FORCEPROP 1 LAST PATH I1691
J 2
(-11030 6613);
DISPLAY 0.808511 (-11030 6613);
PAINT GREEN (-11030 6613);
DISPLAY INVISIBLE (-11030 6613);
FORCEPROP 1 LAST CDS_LMAN_SYM_OUTLINE -50,50,50,-50
J 2
(-10950 6500);
DISPLAY 0.468085 (-10950 6500);
PAINT GREEN (-10950 6500);
DISPLAY INVISIBLE (-10950 6500);
FORCEPROP 1 LAST BOM_IGNORE TRUE
J 2
(-10826 6600);
DISPLAY 0.000000 (-10826 6600);
PAINT GREEN (-10826 6600);
DISPLAY INVISIBLE (-10826 6600);
FORCEPROP 1 LAST JEDEC_TYPE TP010CT020B030_PTH
J 2
(-10826 6600);
DISPLAY 0.000000 (-10826 6600);
PAINT GREEN (-10826 6600);
DISPLAY INVISIBLE (-10826 6600);
FORCEADD OFFPAGE_BI..1
R 6
(-6900 9200);
FORCEPROP 2 LAST $XR0 10E7< 
J 0
(-6840 9200);
DISPLAY 0.638298 (-6840 9200);
PAINT MONO (-6840 9200);
FORCEPROP 2 LAST CDS_LIB cls
J 0
(-6900 9200);
DISPLAY INVISIBLE (-6900 9200);
FORCEPROP 1 LAST CDS_LMAN_SYM_OUTLINE -50,50,50,-50
J 0
(-6900 9200);
DISPLAY 0.468085 (-6900 9200);
PAINT GREEN (-6900 9200);
DISPLAY INVISIBLE (-6900 9200);
FORCEPROP 2 LAST PATH I1692
J 0
(-6850 9300);
DISPLAY 1.021277 (-6850 9300);
DISPLAY INVISIBLE (-6850 9300);
FORCEPROP 1 LAST BODY_TYPE COMMENT
J 0
(-6890 9027);
DISPLAY 0.808511 (-6890 9027);
PAINT GREEN (-6890 9027);
DISPLAY INVISIBLE (-6890 9027);
FORCEPROP 1 LAST OFFPAGE TRUE
J 0
(-6890 9107);
DISPLAY 0.808511 (-6890 9107);
PAINT GREEN (-6890 9107);
DISPLAY INVISIBLE (-6890 9107);
FORCEADD TP_PIONT..1
R 2
(-8250 9200);
FORCEPROP 1 LAST $LOCATION TP47
J 2
(-8350 9200);
DISPLAY 0.808511 (-8350 9200);
PAINT GREEN (-8350 9200);
FORCEPROP 0 LAST CDS_LOCATION TP47
J 0
(-8350 9250);
DISPLAY 1.021277 (-8350 9250);
DISPLAY INVISIBLE (-8350 9250);
FORCEPROP 0 LAST $SEC 1
J 0
(-8350 9250);
DISPLAY 0.680851 (-8350 9250);
PAINT MONO (-8350 9250);
DISPLAY INVISIBLE (-8350 9250);
FORCEPROP 0 LAST CDS_SEC 1
J 0
(-8350 9250);
DISPLAY 1.021277 (-8350 9250);
DISPLAY INVISIBLE (-8350 9250);
FORCEPROP 0 LASTPIN (-8150 9200) $PN 1
J 0
(-8140 9210);
DISPLAY 0.680851 (-8140 9210);
PAINT MONO (-8140 9210);
FORCEPROP 2 LAST CDS_LIB cls
J 0
(-8250 9200);
DISPLAY INVISIBLE (-8250 9200);
FORCEPROP 1 LAST CDS_LMAN_SYM_OUTLINE -50,50,50,-50
J 2
(-8250 9200);
DISPLAY 0.468085 (-8250 9200);
PAINT GREEN (-8250 9200);
DISPLAY INVISIBLE (-8250 9200);
FORCEPROP 1 LAST PATH I1693
J 2
(-8330 9313);
DISPLAY 0.808511 (-8330 9313);
PAINT GREEN (-8330 9313);
DISPLAY INVISIBLE (-8330 9313);
FORCEPROP 1 LAST JEDEC_TYPE TP010CT020B030_PTH
J 2
(-8126 9300);
DISPLAY 0.000000 (-8126 9300);
PAINT GREEN (-8126 9300);
DISPLAY INVISIBLE (-8126 9300);
FORCEPROP 1 LAST BOM_IGNORE TRUE
J 2
(-8126 9300);
DISPLAY 0.000000 (-8126 9300);
PAINT GREEN (-8126 9300);
DISPLAY INVISIBLE (-8126 9300);
FORCEADD OFFPAGE_BI..1
R 6
(-6900 9000);
FORCEPROP 2 LAST $XR0 9E11< 
J 0
(-6840 9000);
DISPLAY 0.638298 (-6840 9000);
PAINT MONO (-6840 9000);
FORCEPROP 1 LAST BODY_TYPE COMMENT
J 0
(-6890 8827);
DISPLAY 0.808511 (-6890 8827);
PAINT GREEN (-6890 8827);
DISPLAY INVISIBLE (-6890 8827);
FORCEPROP 1 LAST OFFPAGE TRUE
J 0
(-6890 8907);
DISPLAY 0.808511 (-6890 8907);
PAINT GREEN (-6890 8907);
DISPLAY INVISIBLE (-6890 8907);
FORCEPROP 2 LAST PATH I1694
J 0
(-6850 9100);
DISPLAY 1.021277 (-6850 9100);
DISPLAY INVISIBLE (-6850 9100);
FORCEPROP 2 LAST CDS_LIB cls
J 0
(-6900 9000);
DISPLAY INVISIBLE (-6900 9000);
FORCEPROP 1 LAST CDS_LMAN_SYM_OUTLINE -50,50,50,-50
J 0
(-6900 9000);
DISPLAY 0.468085 (-6900 9000);
PAINT GREEN (-6900 9000);
DISPLAY INVISIBLE (-6900 9000);
FORCEADD TP_PIONT..1
R 2
(-8250 9000);
FORCEPROP 1 LAST $LOCATION TP48
J 2
(-8350 9000);
DISPLAY 0.808511 (-8350 9000);
PAINT GREEN (-8350 9000);
FORCEPROP 0 LAST CDS_LOCATION TP48
J 0
(-8350 9050);
DISPLAY 1.021277 (-8350 9050);
DISPLAY INVISIBLE (-8350 9050);
FORCEPROP 0 LAST $SEC 1
J 0
(-8350 9050);
DISPLAY 0.680851 (-8350 9050);
PAINT MONO (-8350 9050);
DISPLAY INVISIBLE (-8350 9050);
FORCEPROP 0 LAST CDS_SEC 1
J 0
(-8350 9050);
DISPLAY 1.021277 (-8350 9050);
DISPLAY INVISIBLE (-8350 9050);
FORCEPROP 0 LASTPIN (-8150 9000) $PN 1
J 0
(-8140 9010);
DISPLAY 0.680851 (-8140 9010);
PAINT MONO (-8140 9010);
FORCEPROP 1 LAST JEDEC_TYPE TP010CT020B030_PTH
J 2
(-8126 9100);
DISPLAY 0.000000 (-8126 9100);
PAINT GREEN (-8126 9100);
DISPLAY INVISIBLE (-8126 9100);
FORCEPROP 1 LAST BOM_IGNORE TRUE
J 2
(-8126 9100);
DISPLAY 0.000000 (-8126 9100);
PAINT GREEN (-8126 9100);
DISPLAY INVISIBLE (-8126 9100);
FORCEPROP 1 LAST PATH I1695
J 2
(-8330 9113);
DISPLAY 0.808511 (-8330 9113);
PAINT GREEN (-8330 9113);
DISPLAY INVISIBLE (-8330 9113);
FORCEPROP 2 LAST CDS_LIB cls
J 0
(-8250 9000);
DISPLAY INVISIBLE (-8250 9000);
FORCEPROP 1 LAST CDS_LMAN_SYM_OUTLINE -50,50,50,-50
J 2
(-8250 9000);
DISPLAY 0.468085 (-8250 9000);
PAINT GREEN (-8250 9000);
DISPLAY INVISIBLE (-8250 9000);
FORCEADD OFFPAGE_BI..1
R 6
(-6900 8850);
FORCEPROP 2 LAST $XR0 15E7< 
J 0
(-6840 8850);
DISPLAY 0.638298 (-6840 8850);
PAINT MONO (-6840 8850);
FORCEPROP 1 LAST OFFPAGE TRUE
J 0
(-6890 8757);
DISPLAY 0.808511 (-6890 8757);
PAINT GREEN (-6890 8757);
DISPLAY INVISIBLE (-6890 8757);
FORCEPROP 1 LAST BODY_TYPE COMMENT
J 0
(-6890 8677);
DISPLAY 0.808511 (-6890 8677);
PAINT GREEN (-6890 8677);
DISPLAY INVISIBLE (-6890 8677);
FORCEPROP 1 LAST CDS_LMAN_SYM_OUTLINE -50,50,50,-50
J 0
(-6900 8850);
DISPLAY 0.468085 (-6900 8850);
PAINT GREEN (-6900 8850);
DISPLAY INVISIBLE (-6900 8850);
FORCEPROP 2 LAST CDS_LIB cls
J 0
(-6900 8850);
DISPLAY INVISIBLE (-6900 8850);
FORCEPROP 2 LAST PATH I1698
J 0
(-6850 8950);
DISPLAY 1.021277 (-6850 8950);
DISPLAY INVISIBLE (-6850 8950);
FORCEADD TP_PIONT..1
R 2
(-8250 8850);
FORCEPROP 1 LAST $LOCATION TP49
J 2
(-8350 8850);
DISPLAY 0.808511 (-8350 8850);
PAINT GREEN (-8350 8850);
FORCEPROP 0 LAST CDS_LOCATION TP49
J 0
(-8350 8900);
DISPLAY 1.021277 (-8350 8900);
DISPLAY INVISIBLE (-8350 8900);
FORCEPROP 0 LAST $SEC 1
J 0
(-8350 8900);
DISPLAY 0.680851 (-8350 8900);
PAINT MONO (-8350 8900);
DISPLAY INVISIBLE (-8350 8900);
FORCEPROP 0 LAST CDS_SEC 1
J 0
(-8350 8900);
DISPLAY 1.021277 (-8350 8900);
DISPLAY INVISIBLE (-8350 8900);
FORCEPROP 0 LASTPIN (-8150 8850) $PN 1
J 0
(-8140 8860);
DISPLAY 0.680851 (-8140 8860);
PAINT MONO (-8140 8860);
FORCEPROP 1 LAST BOM_IGNORE TRUE
J 2
(-8126 8950);
DISPLAY 0.000000 (-8126 8950);
PAINT GREEN (-8126 8950);
DISPLAY INVISIBLE (-8126 8950);
FORCEPROP 1 LAST JEDEC_TYPE TP010CT020B030_PTH
J 2
(-8126 8950);
DISPLAY 0.000000 (-8126 8950);
PAINT GREEN (-8126 8950);
DISPLAY INVISIBLE (-8126 8950);
FORCEPROP 1 LAST CDS_LMAN_SYM_OUTLINE -50,50,50,-50
J 2
(-8250 8850);
DISPLAY 0.468085 (-8250 8850);
PAINT GREEN (-8250 8850);
DISPLAY INVISIBLE (-8250 8850);
FORCEPROP 2 LAST CDS_LIB cls
J 0
(-8250 8850);
DISPLAY INVISIBLE (-8250 8850);
FORCEPROP 1 LAST PATH I1699
J 2
(-8330 8963);
DISPLAY 0.808511 (-8330 8963);
PAINT GREEN (-8330 8963);
DISPLAY INVISIBLE (-8330 8963);
FORCEADD OFFPAGE_BI..1
R 6
(-6900 8750);
FORCEPROP 2 LAST $XR0 15H7< 
J 0
(-6840 8750);
DISPLAY 0.638298 (-6840 8750);
PAINT MONO (-6840 8750);
FORCEPROP 1 LAST OFFPAGE TRUE
J 0
(-6890 8657);
DISPLAY 0.808511 (-6890 8657);
PAINT GREEN (-6890 8657);
DISPLAY INVISIBLE (-6890 8657);
FORCEPROP 1 LAST BODY_TYPE COMMENT
J 0
(-6890 8577);
DISPLAY 0.808511 (-6890 8577);
PAINT GREEN (-6890 8577);
DISPLAY INVISIBLE (-6890 8577);
FORCEPROP 1 LAST CDS_LMAN_SYM_OUTLINE -50,50,50,-50
J 0
(-6900 8750);
DISPLAY 0.468085 (-6900 8750);
PAINT GREEN (-6900 8750);
DISPLAY INVISIBLE (-6900 8750);
FORCEPROP 2 LAST CDS_LIB cls
J 0
(-6900 8750);
DISPLAY INVISIBLE (-6900 8750);
FORCEPROP 2 LAST PATH I1700
J 0
(-6850 8850);
DISPLAY 1.021277 (-6850 8850);
DISPLAY INVISIBLE (-6850 8850);
FORCEADD TP_PIONT..1
R 2
(-8250 8750);
FORCEPROP 1 LAST $LOCATION TP50
J 2
(-8350 8750);
DISPLAY 0.808511 (-8350 8750);
PAINT GREEN (-8350 8750);
FORCEPROP 0 LAST CDS_LOCATION TP50
J 0
(-8350 8800);
DISPLAY 1.021277 (-8350 8800);
DISPLAY INVISIBLE (-8350 8800);
FORCEPROP 0 LAST $SEC 1
J 0
(-8350 8800);
DISPLAY 0.680851 (-8350 8800);
PAINT MONO (-8350 8800);
DISPLAY INVISIBLE (-8350 8800);
FORCEPROP 0 LAST CDS_SEC 1
J 0
(-8350 8800);
DISPLAY 1.021277 (-8350 8800);
DISPLAY INVISIBLE (-8350 8800);
FORCEPROP 0 LASTPIN (-8150 8750) $PN 1
J 0
(-8140 8760);
DISPLAY 0.680851 (-8140 8760);
PAINT MONO (-8140 8760);
FORCEPROP 1 LAST BOM_IGNORE TRUE
J 2
(-8126 8850);
DISPLAY 0.000000 (-8126 8850);
PAINT GREEN (-8126 8850);
DISPLAY INVISIBLE (-8126 8850);
FORCEPROP 1 LAST JEDEC_TYPE TP010CT020B030_PTH
J 2
(-8126 8850);
DISPLAY 0.000000 (-8126 8850);
PAINT GREEN (-8126 8850);
DISPLAY INVISIBLE (-8126 8850);
FORCEPROP 1 LAST CDS_LMAN_SYM_OUTLINE -50,50,50,-50
J 2
(-8250 8750);
DISPLAY 0.468085 (-8250 8750);
PAINT GREEN (-8250 8750);
DISPLAY INVISIBLE (-8250 8750);
FORCEPROP 2 LAST CDS_LIB cls
J 0
(-8250 8750);
DISPLAY INVISIBLE (-8250 8750);
FORCEPROP 1 LAST PATH I1701
J 2
(-8330 8863);
DISPLAY 0.808511 (-8330 8863);
PAINT GREEN (-8330 8863);
DISPLAY INVISIBLE (-8330 8863);
FORCEADD OFFPAGE_BI..1
R 6
(-6900 8500);
FORCEPROP 2 LAST $XR0 21D10> 
J 0
(-6840 8500);
DISPLAY 0.638298 (-6840 8500);
PAINT MONO (-6840 8500);
FORCEPROP 2 LAST PATH I1702
J 0
(-6850 8600);
DISPLAY 1.021277 (-6850 8600);
DISPLAY INVISIBLE (-6850 8600);
FORCEPROP 2 LAST CDS_LIB cls
J 0
(-6900 8500);
DISPLAY INVISIBLE (-6900 8500);
FORCEPROP 1 LAST CDS_LMAN_SYM_OUTLINE -50,50,50,-50
J 0
(-6900 8500);
DISPLAY 0.468085 (-6900 8500);
PAINT GREEN (-6900 8500);
DISPLAY INVISIBLE (-6900 8500);
FORCEPROP 1 LAST BODY_TYPE COMMENT
J 0
(-6890 8327);
DISPLAY 0.808511 (-6890 8327);
PAINT GREEN (-6890 8327);
DISPLAY INVISIBLE (-6890 8327);
FORCEPROP 1 LAST OFFPAGE TRUE
J 0
(-6890 8407);
DISPLAY 0.808511 (-6890 8407);
PAINT GREEN (-6890 8407);
DISPLAY INVISIBLE (-6890 8407);
FORCEADD OFFPAGE_BI..1
R 6
(-6900 8400);
FORCEPROP 2 LAST $XR0 21H4> 
J 0
(-6840 8400);
DISPLAY 0.638298 (-6840 8400);
PAINT MONO (-6840 8400);
FORCEPROP 2 LAST PATH I1703
J 0
(-6850 8500);
DISPLAY 1.021277 (-6850 8500);
DISPLAY INVISIBLE (-6850 8500);
FORCEPROP 2 LAST CDS_LIB cls
J 0
(-6900 8400);
DISPLAY INVISIBLE (-6900 8400);
FORCEPROP 1 LAST CDS_LMAN_SYM_OUTLINE -50,50,50,-50
J 0
(-6900 8400);
DISPLAY 0.468085 (-6900 8400);
PAINT GREEN (-6900 8400);
DISPLAY INVISIBLE (-6900 8400);
FORCEPROP 1 LAST BODY_TYPE COMMENT
J 0
(-6890 8227);
DISPLAY 0.808511 (-6890 8227);
PAINT GREEN (-6890 8227);
DISPLAY INVISIBLE (-6890 8227);
FORCEPROP 1 LAST OFFPAGE TRUE
J 0
(-6890 8307);
DISPLAY 0.808511 (-6890 8307);
PAINT GREEN (-6890 8307);
DISPLAY INVISIBLE (-6890 8307);
FORCEADD TP_PIONT..1
R 2
(-8250 8500);
FORCEPROP 1 LAST $LOCATION TP51
J 2
(-8350 8500);
DISPLAY 0.808511 (-8350 8500);
PAINT GREEN (-8350 8500);
FORCEPROP 0 LAST CDS_LOCATION TP51
J 0
(-8350 8550);
DISPLAY 1.021277 (-8350 8550);
DISPLAY INVISIBLE (-8350 8550);
FORCEPROP 0 LAST $SEC 1
J 0
(-8350 8550);
DISPLAY 0.680851 (-8350 8550);
PAINT MONO (-8350 8550);
DISPLAY INVISIBLE (-8350 8550);
FORCEPROP 0 LAST CDS_SEC 1
J 0
(-8350 8550);
DISPLAY 1.021277 (-8350 8550);
DISPLAY INVISIBLE (-8350 8550);
FORCEPROP 0 LASTPIN (-8150 8500) $PN 1
J 0
(-8140 8510);
DISPLAY 0.680851 (-8140 8510);
PAINT MONO (-8140 8510);
FORCEPROP 1 LAST PATH I1704
J 2
(-8330 8613);
DISPLAY 0.808511 (-8330 8613);
PAINT GREEN (-8330 8613);
DISPLAY INVISIBLE (-8330 8613);
FORCEPROP 2 LAST CDS_LIB cls
J 0
(-8250 8500);
DISPLAY INVISIBLE (-8250 8500);
FORCEPROP 1 LAST CDS_LMAN_SYM_OUTLINE -50,50,50,-50
J 2
(-8250 8500);
DISPLAY 0.468085 (-8250 8500);
PAINT GREEN (-8250 8500);
DISPLAY INVISIBLE (-8250 8500);
FORCEPROP 1 LAST JEDEC_TYPE TP010CT020B030_PTH
J 2
(-8126 8600);
DISPLAY 0.000000 (-8126 8600);
PAINT GREEN (-8126 8600);
DISPLAY INVISIBLE (-8126 8600);
FORCEPROP 1 LAST BOM_IGNORE TRUE
J 2
(-8126 8600);
DISPLAY 0.000000 (-8126 8600);
PAINT GREEN (-8126 8600);
DISPLAY INVISIBLE (-8126 8600);
FORCEADD TP_PIONT..1
R 2
(-8250 8400);
FORCEPROP 1 LAST $LOCATION TP62
J 2
(-8350 8400);
DISPLAY 0.808511 (-8350 8400);
PAINT GREEN (-8350 8400);
FORCEPROP 0 LAST CDS_LOCATION TP62
J 0
(-8350 8450);
DISPLAY 1.021277 (-8350 8450);
DISPLAY INVISIBLE (-8350 8450);
FORCEPROP 0 LAST $SEC 1
J 0
(-8350 8450);
DISPLAY 0.680851 (-8350 8450);
PAINT MONO (-8350 8450);
DISPLAY INVISIBLE (-8350 8450);
FORCEPROP 0 LAST CDS_SEC 1
J 0
(-8350 8450);
DISPLAY 1.021277 (-8350 8450);
DISPLAY INVISIBLE (-8350 8450);
FORCEPROP 0 LASTPIN (-8150 8400) $PN 1
J 0
(-8140 8410);
DISPLAY 0.680851 (-8140 8410);
PAINT MONO (-8140 8410);
FORCEPROP 1 LAST PATH I1705
J 2
(-8330 8513);
DISPLAY 0.808511 (-8330 8513);
PAINT GREEN (-8330 8513);
DISPLAY INVISIBLE (-8330 8513);
FORCEPROP 2 LAST CDS_LIB cls
J 0
(-8250 8400);
DISPLAY INVISIBLE (-8250 8400);
FORCEPROP 1 LAST CDS_LMAN_SYM_OUTLINE -50,50,50,-50
J 2
(-8250 8400);
DISPLAY 0.468085 (-8250 8400);
PAINT GREEN (-8250 8400);
DISPLAY INVISIBLE (-8250 8400);
FORCEPROP 1 LAST JEDEC_TYPE TP010CT020B030_PTH
J 2
(-8126 8500);
DISPLAY 0.000000 (-8126 8500);
PAINT GREEN (-8126 8500);
DISPLAY INVISIBLE (-8126 8500);
FORCEPROP 1 LAST BOM_IGNORE TRUE
J 2
(-8126 8500);
DISPLAY 0.000000 (-8126 8500);
PAINT GREEN (-8126 8500);
DISPLAY INVISIBLE (-8126 8500);
FORCEADD RESISTOR..1
(-7150 2950);
FORCEPROP 1 LAST $LOCATION R430
J 2
(-7350 2950);
DISPLAY 1.212766 (-7350 2950);
PAINT GREEN (-7350 2950);
FORCEPROP 0 LAST CDS_LOCATION R430
J 0
(-6900 3050);
DISPLAY 1.021277 (-6900 3050);
DISPLAY INVISIBLE (-6900 3050);
FORCEPROP 0 LAST $SEC 1
J 0
(-6900 3050);
DISPLAY 0.680851 (-6900 3050);
PAINT MONO (-6900 3050);
DISPLAY INVISIBLE (-6900 3050);
FORCEPROP 0 LAST CDS_SEC 1
J 0
(-6900 3050);
DISPLAY 1.021277 (-6900 3050);
DISPLAY INVISIBLE (-6900 3050);
FORCEPROP 0 LASTPIN (-7250 2950) $PN 1
J 2
(-7260 2960);
DISPLAY 0.680851 (-7260 2960);
PAINT MONO (-7260 2960);
FORCEPROP 0 LASTPIN (-7000 2950) $PN 2
J 0
(-6990 2960);
DISPLAY 0.680851 (-6990 2960);
PAINT MONO (-6990 2960);
FORCEPROP 0 LAST PACKAGE 0402
J 0
(-7200 2950);
DISPLAY 0.638298 (-7200 2950);
FORCEPROP 1 LAST VALUE 33OHM
J 0
(-6911 2955);
DISPLAY 1.212766 (-6911 2955);
PAINT GREEN (-6911 2955);
FORCEPROP 1 LAST PATH I1706
J 0
(-7347 3055);
DISPLAY 1.212766 (-7347 3055);
PAINT GREEN (-7347 3055);
DISPLAY INVISIBLE (-7347 3055);
FORCEPROP 1 LAST TOLERANCE 1%
J 0
(-7347 3205);
DISPLAY 1.212766 (-7347 3205);
PAINT GREEN (-7347 3205);
DISPLAY INVISIBLE (-7347 3205);
FORCEPROP 1 LAST CLS_PN G155-133R0-01
J 0
(-7286 3150);
DISPLAY 1.212766 (-7286 3150);
PAINT GREEN (-7286 3150);
DISPLAY INVISIBLE (-7286 3150);
FORCEPROP 1 LAST CDS_LMAN_SYM_OUTLINE -50,50,100,-50
J 0
(-7150 2950);
DISPLAY 0.468085 (-7150 2950);
PAINT GREEN (-7150 2950);
DISPLAY INVISIBLE (-7150 2950);
FORCEPROP 2 LAST CDS_LIB passive
J 0
(-7150 2950);
DISPLAY INVISIBLE (-7150 2950);
FORCEADD RESISTOR..1
(-7150 3250);
FORCEPROP 1 LAST $LOCATION R329
J 2
(-7350 3250);
DISPLAY 1.212766 (-7350 3250);
PAINT GREEN (-7350 3250);
FORCEPROP 0 LAST CDS_LOCATION R329
J 0
(-6900 3350);
DISPLAY 1.021277 (-6900 3350);
DISPLAY INVISIBLE (-6900 3350);
FORCEPROP 0 LAST $SEC 1
J 0
(-6900 3350);
DISPLAY 0.680851 (-6900 3350);
PAINT MONO (-6900 3350);
DISPLAY INVISIBLE (-6900 3350);
FORCEPROP 0 LAST CDS_SEC 1
J 0
(-6900 3350);
DISPLAY 1.021277 (-6900 3350);
DISPLAY INVISIBLE (-6900 3350);
FORCEPROP 0 LASTPIN (-7250 3250) $PN 1
J 2
(-7260 3260);
DISPLAY 0.680851 (-7260 3260);
PAINT MONO (-7260 3260);
FORCEPROP 0 LASTPIN (-7000 3250) $PN 2
J 0
(-6990 3260);
DISPLAY 0.680851 (-6990 3260);
PAINT MONO (-6990 3260);
FORCEPROP 0 LAST PACKAGE 0402
J 0
(-7200 3250);
DISPLAY 0.638298 (-7200 3250);
FORCEPROP 1 LAST VALUE 33OHM
J 0
(-6911 3255);
DISPLAY 1.212766 (-6911 3255);
PAINT GREEN (-6911 3255);
FORCEPROP 1 LAST PATH I1707
J 0
(-7347 3355);
DISPLAY 1.212766 (-7347 3355);
PAINT GREEN (-7347 3355);
DISPLAY INVISIBLE (-7347 3355);
FORCEPROP 1 LAST TOLERANCE 1%
J 0
(-7347 3505);
DISPLAY 1.212766 (-7347 3505);
PAINT GREEN (-7347 3505);
DISPLAY INVISIBLE (-7347 3505);
FORCEPROP 1 LAST CLS_PN G155-133R0-01
J 0
(-7286 3450);
DISPLAY 1.212766 (-7286 3450);
PAINT GREEN (-7286 3450);
DISPLAY INVISIBLE (-7286 3450);
FORCEPROP 1 LAST CDS_LMAN_SYM_OUTLINE -50,50,100,-50
J 0
(-7150 3250);
DISPLAY 0.468085 (-7150 3250);
PAINT GREEN (-7150 3250);
DISPLAY INVISIBLE (-7150 3250);
FORCEPROP 2 LAST CDS_LIB passive
J 0
(-7150 3250);
DISPLAY INVISIBLE (-7150 3250);
FORCEADD RESISTOR..1
(-7150 3150);
FORCEPROP 1 LAST $LOCATION R428
J 2
(-7350 3150);
DISPLAY 1.212766 (-7350 3150);
PAINT GREEN (-7350 3150);
FORCEPROP 0 LAST CDS_LOCATION R428
J 0
(-6900 3250);
DISPLAY 1.021277 (-6900 3250);
DISPLAY INVISIBLE (-6900 3250);
FORCEPROP 0 LAST $SEC 1
J 0
(-6900 3250);
DISPLAY 0.680851 (-6900 3250);
PAINT MONO (-6900 3250);
DISPLAY INVISIBLE (-6900 3250);
FORCEPROP 0 LAST CDS_SEC 1
J 0
(-6900 3250);
DISPLAY 1.021277 (-6900 3250);
DISPLAY INVISIBLE (-6900 3250);
FORCEPROP 0 LASTPIN (-7250 3150) $PN 1
J 2
(-7260 3160);
DISPLAY 0.680851 (-7260 3160);
PAINT MONO (-7260 3160);
FORCEPROP 0 LASTPIN (-7000 3150) $PN 2
J 0
(-6990 3160);
DISPLAY 0.680851 (-6990 3160);
PAINT MONO (-6990 3160);
FORCEPROP 0 LAST PACKAGE 0402
J 0
(-7200 3150);
DISPLAY 0.638298 (-7200 3150);
FORCEPROP 1 LAST VALUE 33OHM
J 0
(-6911 3155);
DISPLAY 1.212766 (-6911 3155);
PAINT GREEN (-6911 3155);
FORCEPROP 2 LAST CDS_LIB passive
J 0
(-7150 3150);
DISPLAY INVISIBLE (-7150 3150);
FORCEPROP 1 LAST CDS_LMAN_SYM_OUTLINE -50,50,100,-50
J 0
(-7150 3150);
DISPLAY 0.468085 (-7150 3150);
PAINT GREEN (-7150 3150);
DISPLAY INVISIBLE (-7150 3150);
FORCEPROP 1 LAST CLS_PN G155-133R0-01
J 0
(-7286 3350);
DISPLAY 1.212766 (-7286 3350);
PAINT GREEN (-7286 3350);
DISPLAY INVISIBLE (-7286 3350);
FORCEPROP 1 LAST TOLERANCE 1%
J 0
(-7347 3405);
DISPLAY 1.212766 (-7347 3405);
PAINT GREEN (-7347 3405);
DISPLAY INVISIBLE (-7347 3405);
FORCEPROP 1 LAST PATH I1708
J 0
(-7347 3255);
DISPLAY 1.212766 (-7347 3255);
PAINT GREEN (-7347 3255);
DISPLAY INVISIBLE (-7347 3255);
FORCEADD RESISTOR..1
(-7150 3050);
FORCEPROP 1 LAST $LOCATION R429
J 2
(-7350 3050);
DISPLAY 1.212766 (-7350 3050);
PAINT GREEN (-7350 3050);
FORCEPROP 0 LAST CDS_LOCATION R429
J 0
(-6900 3150);
DISPLAY 1.021277 (-6900 3150);
DISPLAY INVISIBLE (-6900 3150);
FORCEPROP 0 LAST $SEC 1
J 0
(-6900 3150);
DISPLAY 0.680851 (-6900 3150);
PAINT MONO (-6900 3150);
DISPLAY INVISIBLE (-6900 3150);
FORCEPROP 0 LAST CDS_SEC 1
J 0
(-6900 3150);
DISPLAY 1.021277 (-6900 3150);
DISPLAY INVISIBLE (-6900 3150);
FORCEPROP 0 LASTPIN (-7250 3050) $PN 1
J 2
(-7260 3060);
DISPLAY 0.680851 (-7260 3060);
PAINT MONO (-7260 3060);
FORCEPROP 0 LASTPIN (-7000 3050) $PN 2
J 0
(-6990 3060);
DISPLAY 0.680851 (-6990 3060);
PAINT MONO (-6990 3060);
FORCEPROP 0 LAST PACKAGE 0402
J 0
(-7200 3050);
DISPLAY 0.638298 (-7200 3050);
FORCEPROP 1 LAST VALUE 33OHM
J 0
(-6911 3055);
DISPLAY 1.212766 (-6911 3055);
PAINT GREEN (-6911 3055);
FORCEPROP 1 LAST PATH I1709
J 0
(-7347 3155);
DISPLAY 1.212766 (-7347 3155);
PAINT GREEN (-7347 3155);
DISPLAY INVISIBLE (-7347 3155);
FORCEPROP 1 LAST TOLERANCE 1%
J 0
(-7347 3305);
DISPLAY 1.212766 (-7347 3305);
PAINT GREEN (-7347 3305);
DISPLAY INVISIBLE (-7347 3305);
FORCEPROP 1 LAST CLS_PN G155-133R0-01
J 0
(-7286 3250);
DISPLAY 1.212766 (-7286 3250);
PAINT GREEN (-7286 3250);
DISPLAY INVISIBLE (-7286 3250);
FORCEPROP 1 LAST CDS_LMAN_SYM_OUTLINE -50,50,100,-50
J 0
(-7150 3050);
DISPLAY 0.468085 (-7150 3050);
PAINT GREEN (-7150 3050);
DISPLAY INVISIBLE (-7150 3050);
FORCEPROP 2 LAST CDS_LIB passive
J 0
(-7150 3050);
DISPLAY INVISIBLE (-7150 3050);
FORCEADD RESISTOR..1
(-5100 3250);
FORCEPROP 1 LAST $LOCATION R431
J 2
(-5300 3250);
DISPLAY 1.212766 (-5300 3250);
PAINT GREEN (-5300 3250);
FORCEPROP 0 LAST CDS_LOCATION R431
J 0
(-4850 3350);
DISPLAY 1.021277 (-4850 3350);
DISPLAY INVISIBLE (-4850 3350);
FORCEPROP 0 LAST $SEC 1
J 0
(-4850 3350);
DISPLAY 0.680851 (-4850 3350);
PAINT MONO (-4850 3350);
DISPLAY INVISIBLE (-4850 3350);
FORCEPROP 0 LAST CDS_SEC 1
J 0
(-4850 3350);
DISPLAY 1.021277 (-4850 3350);
DISPLAY INVISIBLE (-4850 3350);
FORCEPROP 0 LASTPIN (-5200 3250) $PN 1
J 2
(-5210 3260);
DISPLAY 0.680851 (-5210 3260);
PAINT MONO (-5210 3260);
FORCEPROP 0 LASTPIN (-4950 3250) $PN 2
J 0
(-4940 3260);
DISPLAY 0.680851 (-4940 3260);
PAINT MONO (-4940 3260);
FORCEPROP 0 LAST PACKAGE 0402
J 0
(-5150 3250);
DISPLAY 0.638298 (-5150 3250);
FORCEPROP 1 LAST VALUE 33OHM
J 0
(-4861 3255);
DISPLAY 1.212766 (-4861 3255);
PAINT GREEN (-4861 3255);
FORCEPROP 1 LAST PATH I1718
J 0
(-5297 3355);
DISPLAY 1.212766 (-5297 3355);
PAINT GREEN (-5297 3355);
DISPLAY INVISIBLE (-5297 3355);
FORCEPROP 1 LAST TOLERANCE 1%
J 0
(-5297 3505);
DISPLAY 1.212766 (-5297 3505);
PAINT GREEN (-5297 3505);
DISPLAY INVISIBLE (-5297 3505);
FORCEPROP 1 LAST CLS_PN G155-133R0-01
J 0
(-5236 3450);
DISPLAY 1.212766 (-5236 3450);
PAINT GREEN (-5236 3450);
DISPLAY INVISIBLE (-5236 3450);
FORCEPROP 1 LAST CDS_LMAN_SYM_OUTLINE -50,50,100,-50
J 0
(-5100 3250);
DISPLAY 0.468085 (-5100 3250);
PAINT GREEN (-5100 3250);
DISPLAY INVISIBLE (-5100 3250);
FORCEPROP 2 LAST CDS_LIB passive
J 0
(-5100 3250);
DISPLAY INVISIBLE (-5100 3250);
FORCEADD RESISTOR..1
(-5100 3150);
FORCEPROP 1 LAST $LOCATION R432
J 2
(-5300 3150);
DISPLAY 1.212766 (-5300 3150);
PAINT GREEN (-5300 3150);
FORCEPROP 0 LAST CDS_LOCATION R432
J 0
(-4850 3250);
DISPLAY 1.021277 (-4850 3250);
DISPLAY INVISIBLE (-4850 3250);
FORCEPROP 0 LAST $SEC 1
J 0
(-4850 3250);
DISPLAY 0.680851 (-4850 3250);
PAINT MONO (-4850 3250);
DISPLAY INVISIBLE (-4850 3250);
FORCEPROP 0 LAST CDS_SEC 1
J 0
(-4850 3250);
DISPLAY 1.021277 (-4850 3250);
DISPLAY INVISIBLE (-4850 3250);
FORCEPROP 0 LASTPIN (-5200 3150) $PN 1
J 2
(-5210 3160);
DISPLAY 0.680851 (-5210 3160);
PAINT MONO (-5210 3160);
FORCEPROP 0 LASTPIN (-4950 3150) $PN 2
J 0
(-4940 3160);
DISPLAY 0.680851 (-4940 3160);
PAINT MONO (-4940 3160);
FORCEPROP 0 LAST PACKAGE 0402
J 0
(-5150 3150);
DISPLAY 0.638298 (-5150 3150);
FORCEPROP 1 LAST VALUE 33OHM
J 0
(-4861 3155);
DISPLAY 1.212766 (-4861 3155);
PAINT GREEN (-4861 3155);
FORCEPROP 2 LAST CDS_LIB passive
J 0
(-5100 3150);
DISPLAY INVISIBLE (-5100 3150);
FORCEPROP 1 LAST CDS_LMAN_SYM_OUTLINE -50,50,100,-50
J 0
(-5100 3150);
DISPLAY 0.468085 (-5100 3150);
PAINT GREEN (-5100 3150);
DISPLAY INVISIBLE (-5100 3150);
FORCEPROP 1 LAST CLS_PN G155-133R0-01
J 0
(-5236 3350);
DISPLAY 1.212766 (-5236 3350);
PAINT GREEN (-5236 3350);
DISPLAY INVISIBLE (-5236 3350);
FORCEPROP 1 LAST TOLERANCE 1%
J 0
(-5297 3405);
DISPLAY 1.212766 (-5297 3405);
PAINT GREEN (-5297 3405);
DISPLAY INVISIBLE (-5297 3405);
FORCEPROP 1 LAST PATH I1719
J 0
(-5297 3255);
DISPLAY 1.212766 (-5297 3255);
PAINT GREEN (-5297 3255);
DISPLAY INVISIBLE (-5297 3255);
FORCEADD RESISTOR..1
(-5100 3050);
FORCEPROP 1 LAST $LOCATION R433
J 2
(-5300 3050);
DISPLAY 1.212766 (-5300 3050);
PAINT GREEN (-5300 3050);
FORCEPROP 0 LAST CDS_LOCATION R433
J 0
(-4850 3150);
DISPLAY 1.021277 (-4850 3150);
DISPLAY INVISIBLE (-4850 3150);
FORCEPROP 0 LAST $SEC 1
J 0
(-4850 3150);
DISPLAY 0.680851 (-4850 3150);
PAINT MONO (-4850 3150);
DISPLAY INVISIBLE (-4850 3150);
FORCEPROP 0 LAST CDS_SEC 1
J 0
(-4850 3150);
DISPLAY 1.021277 (-4850 3150);
DISPLAY INVISIBLE (-4850 3150);
FORCEPROP 0 LASTPIN (-5200 3050) $PN 1
J 2
(-5210 3060);
DISPLAY 0.680851 (-5210 3060);
PAINT MONO (-5210 3060);
FORCEPROP 0 LASTPIN (-4950 3050) $PN 2
J 0
(-4940 3060);
DISPLAY 0.680851 (-4940 3060);
PAINT MONO (-4940 3060);
FORCEPROP 0 LAST PACKAGE 0402
J 0
(-5150 3050);
DISPLAY 0.638298 (-5150 3050);
FORCEPROP 1 LAST VALUE 33OHM
J 0
(-4861 3055);
DISPLAY 1.212766 (-4861 3055);
PAINT GREEN (-4861 3055);
FORCEPROP 1 LAST PATH I1720
J 0
(-5297 3155);
DISPLAY 1.212766 (-5297 3155);
PAINT GREEN (-5297 3155);
DISPLAY INVISIBLE (-5297 3155);
FORCEPROP 1 LAST TOLERANCE 1%
J 0
(-5297 3305);
DISPLAY 1.212766 (-5297 3305);
PAINT GREEN (-5297 3305);
DISPLAY INVISIBLE (-5297 3305);
FORCEPROP 1 LAST CLS_PN G155-133R0-01
J 0
(-5236 3250);
DISPLAY 1.212766 (-5236 3250);
PAINT GREEN (-5236 3250);
DISPLAY INVISIBLE (-5236 3250);
FORCEPROP 1 LAST CDS_LMAN_SYM_OUTLINE -50,50,100,-50
J 0
(-5100 3050);
DISPLAY 0.468085 (-5100 3050);
PAINT GREEN (-5100 3050);
DISPLAY INVISIBLE (-5100 3050);
FORCEPROP 2 LAST CDS_LIB passive
J 0
(-5100 3050);
DISPLAY INVISIBLE (-5100 3050);
FORCEADD RESISTOR..1
(-5100 2950);
FORCEPROP 1 LAST $LOCATION R434
J 2
(-5300 2950);
DISPLAY 1.212766 (-5300 2950);
PAINT GREEN (-5300 2950);
FORCEPROP 0 LAST CDS_LOCATION R434
J 0
(-4850 3050);
DISPLAY 1.021277 (-4850 3050);
DISPLAY INVISIBLE (-4850 3050);
FORCEPROP 0 LAST $SEC 1
J 0
(-4850 3050);
DISPLAY 0.680851 (-4850 3050);
PAINT MONO (-4850 3050);
DISPLAY INVISIBLE (-4850 3050);
FORCEPROP 0 LAST CDS_SEC 1
J 0
(-4850 3050);
DISPLAY 1.021277 (-4850 3050);
DISPLAY INVISIBLE (-4850 3050);
FORCEPROP 0 LASTPIN (-5200 2950) $PN 1
J 2
(-5210 2960);
DISPLAY 0.680851 (-5210 2960);
PAINT MONO (-5210 2960);
FORCEPROP 0 LASTPIN (-4950 2950) $PN 2
J 0
(-4940 2960);
DISPLAY 0.680851 (-4940 2960);
PAINT MONO (-4940 2960);
FORCEPROP 0 LAST PACKAGE 0402
J 0
(-5150 2950);
DISPLAY 0.638298 (-5150 2950);
FORCEPROP 1 LAST VALUE 33OHM
J 0
(-4861 2955);
DISPLAY 1.212766 (-4861 2955);
PAINT GREEN (-4861 2955);
FORCEPROP 1 LAST PATH I1721
J 0
(-5297 3055);
DISPLAY 1.212766 (-5297 3055);
PAINT GREEN (-5297 3055);
DISPLAY INVISIBLE (-5297 3055);
FORCEPROP 1 LAST TOLERANCE 1%
J 0
(-5297 3205);
DISPLAY 1.212766 (-5297 3205);
PAINT GREEN (-5297 3205);
DISPLAY INVISIBLE (-5297 3205);
FORCEPROP 1 LAST CLS_PN G155-133R0-01
J 0
(-5236 3150);
DISPLAY 1.212766 (-5236 3150);
PAINT GREEN (-5236 3150);
DISPLAY INVISIBLE (-5236 3150);
FORCEPROP 1 LAST CDS_LMAN_SYM_OUTLINE -50,50,100,-50
J 0
(-5100 2950);
DISPLAY 0.468085 (-5100 2950);
PAINT GREEN (-5100 2950);
DISPLAY INVISIBLE (-5100 2950);
FORCEPROP 2 LAST CDS_LIB passive
J 0
(-5100 2950);
DISPLAY INVISIBLE (-5100 2950);
FORCEADD VCC..1
(-6500 3800);
FORCEPROP 3 LASTPIN (-6450 3750) SIG_NAME XP3R3V_FPGA\g
J 0
(-6440 3760);
DISPLAY 0.659574 (-6440 3760);
PAINT MONO (-6440 3760);
DISPLAY INVISIBLE (-6440 3760);
FORCEPROP 0 LAST VOLTAGE 3.3V
J 0
(-6700 3900);
DISPLAY 1.021277 (-6700 3900);
DISPLAY BOTH (-6700 3900);
FORCEPROP 1 LAST HDL_POWER XP3R3V_FPGA
J 1
(-6445 3855);
DISPLAY 1.021277 (-6445 3855);
PAINT GREEN (-6445 3855);
FORCEPROP 1 LAST PATH I1722
J 0
(-6465 3890);
DISPLAY 0.808511 (-6465 3890);
PAINT GREEN (-6465 3890);
DISPLAY INVISIBLE (-6465 3890);
FORCEPROP 2 LAST CDS_LIB cls
J 0
(-6500 3800);
DISPLAY INVISIBLE (-6500 3800);
FORCEPROP 1 LAST CDS_LMAN_SYM_OUTLINE -250,250,250,-250
J 0
(-6500 3800);
DISPLAY 0.468085 (-6500 3800);
PAINT GREEN (-6500 3800);
DISPLAY INVISIBLE (-6500 3800);
FORCEPROP 1 LAST BODY_TYPE PLUMBING
J 0
(-6545 3757);
DISPLAY 0.340426 (-6545 3757);
PAINT GREEN (-6545 3757);
DISPLAY INVISIBLE (-6545 3757);
FORCEADD GND_SG..1
(-6500 2700);
FORCEPROP 3 LASTPIN (-6450 2750) SIG_NAME SG\g
J 0
(-6440 2760);
DISPLAY 0.659574 (-6440 2760);
PAINT MONO (-6440 2760);
DISPLAY INVISIBLE (-6440 2760);
FORCEPROP 1 LAST HDL_POWER SG
J 1
(-6445 2605);
DISPLAY 0.808511 (-6445 2605);
PAINT GREEN (-6445 2605);
FORCEPROP 1 LAST PATH I1723
J 0
(-6465 2700);
DISPLAY 0.808511 (-6465 2700);
PAINT GREEN (-6465 2700);
DISPLAY INVISIBLE (-6465 2700);
FORCEPROP 1 LAST BODY_TYPE PLUMBING
J 0
(-6485 2685);
DISPLAY 0.808511 (-6485 2685);
PAINT GREEN (-6485 2685);
DISPLAY INVISIBLE (-6485 2685);
FORCEPROP 1 LAST CDS_LMAN_SYM_OUTLINE 0,0,100,-50
J 0
(-6500 2700);
DISPLAY 0.468085 (-6500 2700);
PAINT GREEN (-6500 2700);
DISPLAY INVISIBLE (-6500 2700);
FORCEPROP 2 LAST CDS_LIB cls
J 0
(-6500 2700);
DISPLAY INVISIBLE (-6500 2700);
FORCEADD GND_SG..1
(-5800 2700);
FORCEPROP 3 LASTPIN (-5750 2750) SIG_NAME SG\g
J 0
(-5740 2760);
DISPLAY 0.659574 (-5740 2760);
PAINT MONO (-5740 2760);
DISPLAY INVISIBLE (-5740 2760);
FORCEPROP 1 LAST HDL_POWER SG
J 1
(-5750 2600);
DISPLAY 0.808511 (-5750 2600);
PAINT GREEN (-5750 2600);
FORCEPROP 1 LAST BODY_TYPE PLUMBING
J 0
(-5785 2685);
DISPLAY 0.808511 (-5785 2685);
PAINT GREEN (-5785 2685);
DISPLAY INVISIBLE (-5785 2685);
FORCEPROP 1 LAST CDS_LMAN_SYM_OUTLINE 0,0,100,-50
J 0
(-5800 2700);
DISPLAY 0.468085 (-5800 2700);
PAINT GREEN (-5800 2700);
DISPLAY INVISIBLE (-5800 2700);
FORCEPROP 1 LAST PATH I1724
J 0
(-5765 2700);
DISPLAY 0.808511 (-5765 2700);
PAINT GREEN (-5765 2700);
DISPLAY INVISIBLE (-5765 2700);
FORCEPROP 2 LAST CDS_LIB cls
J 0
(-5800 2700);
DISPLAY INVISIBLE (-5800 2700);
FORCEADD OFFPAGE_BI..1
R 4
(-8400 2950);
FORCEPROP 2 LAST $XR1 25J5<> 
J 0
(-8829 2950);
DISPLAY 0.638298 (-8829 2950);
PAINT MONO (-8829 2950);
FORCEPROP 2 LAST $XR0 12E5<> 
J 0
(-8619 2950);
DISPLAY 0.638298 (-8619 2950);
PAINT MONO (-8619 2950);
FORCEPROP 2 LAST CDS_LIB cls
J 0
(-8400 2950);
DISPLAY INVISIBLE (-8400 2950);
FORCEPROP 2 LAST PATH I1733
J 0
(-8350 3050);
DISPLAY 1.021277 (-8350 3050);
DISPLAY INVISIBLE (-8350 3050);
FORCEPROP 1 LAST CDS_LMAN_SYM_OUTLINE -50,50,50,-50
R 2
J 0
(-8400 2950);
DISPLAY 0.468085 (-8400 2950);
PAINT GREEN (-8400 2950);
DISPLAY INVISIBLE (-8400 2950);
FORCEPROP 1 LAST OFFPAGE TRUE
R 2
J 0
(-8410 2895);
DISPLAY 0.808511 (-8410 2895);
PAINT GREEN (-8410 2895);
DISPLAY INVISIBLE (-8410 2895);
FORCEPROP 1 LAST BODY_TYPE COMMENT
R 2
J 0
(-8410 2815);
DISPLAY 0.808511 (-8410 2815);
PAINT GREEN (-8410 2815);
DISPLAY INVISIBLE (-8410 2815);
FORCEADD OFFPAGE_BI..1
R 4
(-8400 3050);
FORCEPROP 2 LAST $XR1 25K5<> 
J 0
(-8829 3050);
DISPLAY 0.638298 (-8829 3050);
PAINT MONO (-8829 3050);
FORCEPROP 2 LAST $XR0 12E5<> 
J 0
(-8619 3050);
DISPLAY 0.638298 (-8619 3050);
PAINT MONO (-8619 3050);
FORCEPROP 2 LAST CDS_LIB cls
J 0
(-8400 3050);
DISPLAY INVISIBLE (-8400 3050);
FORCEPROP 2 LAST PATH I1734
J 0
(-8350 3150);
DISPLAY 1.021277 (-8350 3150);
DISPLAY INVISIBLE (-8350 3150);
FORCEPROP 1 LAST CDS_LMAN_SYM_OUTLINE -50,50,50,-50
R 2
J 0
(-8400 3050);
DISPLAY 0.468085 (-8400 3050);
PAINT GREEN (-8400 3050);
DISPLAY INVISIBLE (-8400 3050);
FORCEPROP 1 LAST OFFPAGE TRUE
R 2
J 0
(-8410 2995);
DISPLAY 0.808511 (-8410 2995);
PAINT GREEN (-8410 2995);
DISPLAY INVISIBLE (-8410 2995);
FORCEPROP 1 LAST BODY_TYPE COMMENT
R 2
J 0
(-8410 2915);
DISPLAY 0.808511 (-8410 2915);
PAINT GREEN (-8410 2915);
DISPLAY INVISIBLE (-8410 2915);
FORCEADD OFFPAGE_BI..1
R 4
(-8400 3250);
FORCEPROP 2 LAST $XR1 25K5<> 
J 0
(-8829 3250);
DISPLAY 0.638298 (-8829 3250);
PAINT MONO (-8829 3250);
FORCEPROP 2 LAST $XR0 12F5<> 
J 0
(-8619 3250);
DISPLAY 0.638298 (-8619 3250);
PAINT MONO (-8619 3250);
FORCEPROP 2 LAST CDS_LIB cls
J 0
(-8400 3250);
DISPLAY INVISIBLE (-8400 3250);
FORCEPROP 2 LAST PATH I1735
J 0
(-8350 3350);
DISPLAY 1.021277 (-8350 3350);
DISPLAY INVISIBLE (-8350 3350);
FORCEPROP 1 LAST CDS_LMAN_SYM_OUTLINE -50,50,50,-50
R 2
J 0
(-8400 3250);
DISPLAY 0.468085 (-8400 3250);
PAINT GREEN (-8400 3250);
DISPLAY INVISIBLE (-8400 3250);
FORCEPROP 1 LAST OFFPAGE TRUE
R 2
J 0
(-8410 3195);
DISPLAY 0.808511 (-8410 3195);
PAINT GREEN (-8410 3195);
DISPLAY INVISIBLE (-8410 3195);
FORCEPROP 1 LAST BODY_TYPE COMMENT
R 2
J 0
(-8410 3115);
DISPLAY 0.808511 (-8410 3115);
PAINT GREEN (-8410 3115);
DISPLAY INVISIBLE (-8410 3115);
FORCEADD OFFPAGE_BI..1
R 4
(-8400 3150);
FORCEPROP 2 LAST $XR1 25K5<> 
J 0
(-8829 3150);
DISPLAY 0.638298 (-8829 3150);
PAINT MONO (-8829 3150);
FORCEPROP 2 LAST $XR0 12E5<> 
J 0
(-8619 3150);
DISPLAY 0.638298 (-8619 3150);
PAINT MONO (-8619 3150);
FORCEPROP 2 LAST CDS_LIB cls
J 0
(-8400 3150);
DISPLAY INVISIBLE (-8400 3150);
FORCEPROP 2 LAST PATH I1736
J 0
(-8350 3250);
DISPLAY 1.021277 (-8350 3250);
DISPLAY INVISIBLE (-8350 3250);
FORCEPROP 1 LAST CDS_LMAN_SYM_OUTLINE -50,50,50,-50
R 2
J 0
(-8400 3150);
DISPLAY 0.468085 (-8400 3150);
PAINT GREEN (-8400 3150);
DISPLAY INVISIBLE (-8400 3150);
FORCEPROP 1 LAST OFFPAGE TRUE
R 2
J 0
(-8410 3095);
DISPLAY 0.808511 (-8410 3095);
PAINT GREEN (-8410 3095);
DISPLAY INVISIBLE (-8410 3095);
FORCEPROP 1 LAST BODY_TYPE COMMENT
R 2
J 0
(-8410 3015);
DISPLAY 0.808511 (-8410 3015);
PAINT GREEN (-8410 3015);
DISPLAY INVISIBLE (-8410 3015);
FORCEADD OFFPAGE_BI..1
R 6
(-3800 2950);
FORCEPROP 2 LAST $XR0 12E5<> 
J 0
(-3740 2950);
DISPLAY 0.638298 (-3740 2950);
PAINT MONO (-3740 2950);
FORCEPROP 2 LAST $XR1 25H5<> 
J 0
(-3530 2950);
DISPLAY 0.638298 (-3530 2950);
PAINT MONO (-3530 2950);
FORCEPROP 1 LAST OFFPAGE TRUE
J 0
(-3790 2857);
DISPLAY 0.808511 (-3790 2857);
PAINT GREEN (-3790 2857);
DISPLAY INVISIBLE (-3790 2857);
FORCEPROP 1 LAST BODY_TYPE COMMENT
J 0
(-3790 2777);
DISPLAY 0.808511 (-3790 2777);
PAINT GREEN (-3790 2777);
DISPLAY INVISIBLE (-3790 2777);
FORCEPROP 1 LAST CDS_LMAN_SYM_OUTLINE -50,50,50,-50
J 0
(-3800 2950);
DISPLAY 0.468085 (-3800 2950);
PAINT GREEN (-3800 2950);
DISPLAY INVISIBLE (-3800 2950);
FORCEPROP 2 LAST PATH I1737
J 0
(-3750 3050);
DISPLAY 1.021277 (-3750 3050);
DISPLAY INVISIBLE (-3750 3050);
FORCEPROP 2 LAST CDS_LIB cls
J 0
(-3800 2950);
DISPLAY INVISIBLE (-3800 2950);
FORCEADD OFFPAGE_BI..1
R 6
(-3800 3250);
FORCEPROP 2 LAST $XR0 12E5<> 
J 0
(-3740 3250);
DISPLAY 0.638298 (-3740 3250);
PAINT MONO (-3740 3250);
FORCEPROP 2 LAST $XR1 25J5<> 
J 0
(-3530 3250);
DISPLAY 0.638298 (-3530 3250);
PAINT MONO (-3530 3250);
FORCEPROP 2 LAST CDS_LIB cls
J 0
(-3800 3250);
DISPLAY INVISIBLE (-3800 3250);
FORCEPROP 2 LAST PATH I1738
J 0
(-3750 3350);
DISPLAY 1.021277 (-3750 3350);
DISPLAY INVISIBLE (-3750 3350);
FORCEPROP 1 LAST CDS_LMAN_SYM_OUTLINE -50,50,50,-50
J 0
(-3800 3250);
DISPLAY 0.468085 (-3800 3250);
PAINT GREEN (-3800 3250);
DISPLAY INVISIBLE (-3800 3250);
FORCEPROP 1 LAST BODY_TYPE COMMENT
J 0
(-3790 3077);
DISPLAY 0.808511 (-3790 3077);
PAINT GREEN (-3790 3077);
DISPLAY INVISIBLE (-3790 3077);
FORCEPROP 1 LAST OFFPAGE TRUE
J 0
(-3790 3157);
DISPLAY 0.808511 (-3790 3157);
PAINT GREEN (-3790 3157);
DISPLAY INVISIBLE (-3790 3157);
FORCEADD OFFPAGE_BI..1
R 6
(-3800 3150);
FORCEPROP 2 LAST $XR0 12E5<> 
J 0
(-3740 3150);
DISPLAY 0.638298 (-3740 3150);
PAINT MONO (-3740 3150);
FORCEPROP 2 LAST $XR1 25J5<> 
J 0
(-3530 3150);
DISPLAY 0.638298 (-3530 3150);
PAINT MONO (-3530 3150);
FORCEPROP 2 LAST CDS_LIB cls
J 0
(-3800 3150);
DISPLAY INVISIBLE (-3800 3150);
FORCEPROP 2 LAST PATH I1739
J 0
(-3750 3250);
DISPLAY 1.021277 (-3750 3250);
DISPLAY INVISIBLE (-3750 3250);
FORCEPROP 1 LAST CDS_LMAN_SYM_OUTLINE -50,50,50,-50
J 0
(-3800 3150);
DISPLAY 0.468085 (-3800 3150);
PAINT GREEN (-3800 3150);
DISPLAY INVISIBLE (-3800 3150);
FORCEPROP 1 LAST BODY_TYPE COMMENT
J 0
(-3790 2977);
DISPLAY 0.808511 (-3790 2977);
PAINT GREEN (-3790 2977);
DISPLAY INVISIBLE (-3790 2977);
FORCEPROP 1 LAST OFFPAGE TRUE
J 0
(-3790 3057);
DISPLAY 0.808511 (-3790 3057);
PAINT GREEN (-3790 3057);
DISPLAY INVISIBLE (-3790 3057);
FORCEADD OFFPAGE_BI..1
R 6
(-3800 3050);
FORCEPROP 2 LAST $XR0 12E5<> 
J 0
(-3740 3050);
DISPLAY 0.638298 (-3740 3050);
PAINT MONO (-3740 3050);
FORCEPROP 2 LAST $XR1 25J5<> 
J 0
(-3530 3050);
DISPLAY 0.638298 (-3530 3050);
PAINT MONO (-3530 3050);
FORCEPROP 1 LAST BODY_TYPE COMMENT
J 0
(-3790 2877);
DISPLAY 0.808511 (-3790 2877);
PAINT GREEN (-3790 2877);
DISPLAY INVISIBLE (-3790 2877);
FORCEPROP 1 LAST OFFPAGE TRUE
J 0
(-3790 2957);
DISPLAY 0.808511 (-3790 2957);
PAINT GREEN (-3790 2957);
DISPLAY INVISIBLE (-3790 2957);
FORCEPROP 1 LAST CDS_LMAN_SYM_OUTLINE -50,50,50,-50
J 0
(-3800 3050);
DISPLAY 0.468085 (-3800 3050);
PAINT GREEN (-3800 3050);
DISPLAY INVISIBLE (-3800 3050);
FORCEPROP 2 LAST PATH I1740
J 0
(-3750 3150);
DISPLAY 1.021277 (-3750 3150);
DISPLAY INVISIBLE (-3750 3150);
FORCEPROP 2 LAST CDS_LIB cls
J 0
(-3800 3050);
DISPLAY INVISIBLE (-3800 3050);
FORCEADD OFFPAGE_BI..1
R 6
(-12300 7400);
FORCEPROP 2 LAST $XR0 13J11<> 
J 0
(-12240 7400);
DISPLAY 0.638298 (-12240 7400);
PAINT MONO (-12240 7400);
FORCEPROP 1 LAST BODY_TYPE COMMENT
J 0
(-12290 7227);
DISPLAY 0.808511 (-12290 7227);
PAINT GREEN (-12290 7227);
DISPLAY INVISIBLE (-12290 7227);
FORCEPROP 1 LAST CDS_LMAN_SYM_OUTLINE -50,50,50,-50
J 0
(-12300 7400);
DISPLAY 0.468085 (-12300 7400);
PAINT GREEN (-12300 7400);
DISPLAY INVISIBLE (-12300 7400);
FORCEPROP 2 LAST CDS_LIB cls
J 0
(-12300 7400);
DISPLAY INVISIBLE (-12300 7400);
FORCEPROP 1 LAST OFFPAGE TRUE
J 0
(-12290 7307);
DISPLAY 0.808511 (-12290 7307);
PAINT GREEN (-12290 7307);
DISPLAY INVISIBLE (-12290 7307);
FORCEPROP 2 LAST PATH I905
J 0
(-12200 7450);
DISPLAY 1.021277 (-12200 7450);
DISPLAY INVISIBLE (-12200 7450);
FORCEADD OFFPAGE_BI..1
R 6
(-12300 7600);
FORCEPROP 2 LAST $XR0 13J11<> 
J 0
(-12240 7600);
DISPLAY 0.638298 (-12240 7600);
PAINT MONO (-12240 7600);
FORCEPROP 1 LAST BODY_TYPE COMMENT
J 0
(-12290 7427);
DISPLAY 0.808511 (-12290 7427);
PAINT GREEN (-12290 7427);
DISPLAY INVISIBLE (-12290 7427);
FORCEPROP 1 LAST CDS_LMAN_SYM_OUTLINE -50,50,50,-50
J 0
(-12300 7600);
DISPLAY 0.468085 (-12300 7600);
PAINT GREEN (-12300 7600);
DISPLAY INVISIBLE (-12300 7600);
FORCEPROP 2 LAST CDS_LIB cls
J 0
(-12300 7600);
DISPLAY INVISIBLE (-12300 7600);
FORCEPROP 1 LAST OFFPAGE TRUE
J 0
(-12290 7507);
DISPLAY 0.808511 (-12290 7507);
PAINT GREEN (-12290 7507);
DISPLAY INVISIBLE (-12290 7507);
FORCEPROP 2 LAST PATH I906
J 0
(-12200 7650);
DISPLAY 1.021277 (-12200 7650);
DISPLAY INVISIBLE (-12200 7650);
FORCEADD OFFPAGE_BI..1
R 6
(-12300 7700);
FORCEPROP 2 LAST $XR0 13J11<> 
J 0
(-12240 7700);
DISPLAY 0.638298 (-12240 7700);
PAINT MONO (-12240 7700);
FORCEPROP 1 LAST BODY_TYPE COMMENT
J 0
(-12290 7527);
DISPLAY 0.808511 (-12290 7527);
PAINT GREEN (-12290 7527);
DISPLAY INVISIBLE (-12290 7527);
FORCEPROP 1 LAST CDS_LMAN_SYM_OUTLINE -50,50,50,-50
J 0
(-12300 7700);
DISPLAY 0.468085 (-12300 7700);
PAINT GREEN (-12300 7700);
DISPLAY INVISIBLE (-12300 7700);
FORCEPROP 2 LAST CDS_LIB cls
J 0
(-12300 7700);
DISPLAY INVISIBLE (-12300 7700);
FORCEPROP 1 LAST OFFPAGE TRUE
J 0
(-12290 7607);
DISPLAY 0.808511 (-12290 7607);
PAINT GREEN (-12290 7607);
DISPLAY INVISIBLE (-12290 7607);
FORCEPROP 2 LAST PATH I907
J 0
(-12200 7750);
DISPLAY 1.021277 (-12200 7750);
DISPLAY INVISIBLE (-12200 7750);
FORCEADD OFFPAGE_BI..1
R 6
(-12300 7500);
FORCEPROP 2 LAST $XR0 13J11<> 
J 0
(-12240 7500);
DISPLAY 0.638298 (-12240 7500);
PAINT MONO (-12240 7500);
FORCEPROP 1 LAST BODY_TYPE COMMENT
J 0
(-12290 7327);
DISPLAY 0.808511 (-12290 7327);
PAINT GREEN (-12290 7327);
DISPLAY INVISIBLE (-12290 7327);
FORCEPROP 1 LAST CDS_LMAN_SYM_OUTLINE -50,50,50,-50
J 0
(-12300 7500);
DISPLAY 0.468085 (-12300 7500);
PAINT GREEN (-12300 7500);
DISPLAY INVISIBLE (-12300 7500);
FORCEPROP 2 LAST CDS_LIB cls
J 0
(-12300 7500);
DISPLAY INVISIBLE (-12300 7500);
FORCEPROP 1 LAST OFFPAGE TRUE
J 0
(-12290 7407);
DISPLAY 0.808511 (-12290 7407);
PAINT GREEN (-12290 7407);
DISPLAY INVISIBLE (-12290 7407);
FORCEPROP 2 LAST PATH I908
J 0
(-12200 7550);
DISPLAY 1.021277 (-12200 7550);
DISPLAY INVISIBLE (-12200 7550);
FORCEADD OFFPAGE_BI..1
R 6
(-12300 8000);
FORCEPROP 2 LAST $XR0 13H11<> 
J 0
(-12240 8000);
DISPLAY 0.638298 (-12240 8000);
PAINT MONO (-12240 8000);
FORCEPROP 1 LAST BODY_TYPE COMMENT
J 0
(-12290 7827);
DISPLAY 0.808511 (-12290 7827);
PAINT GREEN (-12290 7827);
DISPLAY INVISIBLE (-12290 7827);
FORCEPROP 1 LAST CDS_LMAN_SYM_OUTLINE -50,50,50,-50
J 0
(-12300 8000);
DISPLAY 0.468085 (-12300 8000);
PAINT GREEN (-12300 8000);
DISPLAY INVISIBLE (-12300 8000);
FORCEPROP 2 LAST CDS_LIB cls
J 0
(-12300 8000);
DISPLAY INVISIBLE (-12300 8000);
FORCEPROP 1 LAST OFFPAGE TRUE
J 0
(-12290 7907);
DISPLAY 0.808511 (-12290 7907);
PAINT GREEN (-12290 7907);
DISPLAY INVISIBLE (-12290 7907);
FORCEPROP 2 LAST PATH I909
J 0
(-12200 8050);
DISPLAY 1.021277 (-12200 8050);
DISPLAY INVISIBLE (-12200 8050);
FORCEADD OFFPAGE_BI..1
R 6
(-12300 7900);
FORCEPROP 2 LAST $XR0 13H11<> 
J 0
(-12240 7900);
DISPLAY 0.638298 (-12240 7900);
PAINT MONO (-12240 7900);
FORCEPROP 1 LAST BODY_TYPE COMMENT
J 0
(-12290 7727);
DISPLAY 0.808511 (-12290 7727);
PAINT GREEN (-12290 7727);
DISPLAY INVISIBLE (-12290 7727);
FORCEPROP 1 LAST CDS_LMAN_SYM_OUTLINE -50,50,50,-50
J 0
(-12300 7900);
DISPLAY 0.468085 (-12300 7900);
PAINT GREEN (-12300 7900);
DISPLAY INVISIBLE (-12300 7900);
FORCEPROP 2 LAST CDS_LIB cls
J 0
(-12300 7900);
DISPLAY INVISIBLE (-12300 7900);
FORCEPROP 1 LAST OFFPAGE TRUE
J 0
(-12290 7807);
DISPLAY 0.808511 (-12290 7807);
PAINT GREEN (-12290 7807);
DISPLAY INVISIBLE (-12290 7807);
FORCEPROP 2 LAST PATH I910
J 0
(-12200 7950);
DISPLAY 1.021277 (-12200 7950);
DISPLAY INVISIBLE (-12200 7950);
FORCEADD OFFPAGE_BI..1
R 6
(-12300 8200);
FORCEPROP 2 LAST $XR0 13H11<> 
J 0
(-12240 8200);
DISPLAY 0.638298 (-12240 8200);
PAINT MONO (-12240 8200);
FORCEPROP 1 LAST BODY_TYPE COMMENT
J 0
(-12290 8027);
DISPLAY 0.808511 (-12290 8027);
PAINT GREEN (-12290 8027);
DISPLAY INVISIBLE (-12290 8027);
FORCEPROP 1 LAST CDS_LMAN_SYM_OUTLINE -50,50,50,-50
J 0
(-12300 8200);
DISPLAY 0.468085 (-12300 8200);
PAINT GREEN (-12300 8200);
DISPLAY INVISIBLE (-12300 8200);
FORCEPROP 2 LAST CDS_LIB cls
J 0
(-12300 8200);
DISPLAY INVISIBLE (-12300 8200);
FORCEPROP 1 LAST OFFPAGE TRUE
J 0
(-12290 8107);
DISPLAY 0.808511 (-12290 8107);
PAINT GREEN (-12290 8107);
DISPLAY INVISIBLE (-12290 8107);
FORCEPROP 2 LAST PATH I911
J 0
(-12200 8250);
DISPLAY 1.021277 (-12200 8250);
DISPLAY INVISIBLE (-12200 8250);
FORCEADD OFFPAGE_BI..1
R 6
(-12300 7800);
FORCEPROP 2 LAST $XR0 13J11<> 
J 0
(-12240 7800);
DISPLAY 0.638298 (-12240 7800);
PAINT MONO (-12240 7800);
FORCEPROP 2 LAST CDS_LIB cls
J 0
(-12300 7800);
DISPLAY INVISIBLE (-12300 7800);
FORCEPROP 1 LAST CDS_LMAN_SYM_OUTLINE -50,50,50,-50
J 0
(-12300 7800);
DISPLAY 0.468085 (-12300 7800);
PAINT GREEN (-12300 7800);
DISPLAY INVISIBLE (-12300 7800);
FORCEPROP 1 LAST BODY_TYPE COMMENT
J 0
(-12290 7627);
DISPLAY 0.808511 (-12290 7627);
PAINT GREEN (-12290 7627);
DISPLAY INVISIBLE (-12290 7627);
FORCEPROP 1 LAST OFFPAGE TRUE
J 0
(-12290 7707);
DISPLAY 0.808511 (-12290 7707);
PAINT GREEN (-12290 7707);
DISPLAY INVISIBLE (-12290 7707);
FORCEPROP 2 LAST PATH I912
J 0
(-12200 7850);
DISPLAY 1.021277 (-12200 7850);
DISPLAY INVISIBLE (-12200 7850);
FORCEADD OFFPAGE_BI..1
R 6
(-12300 8100);
FORCEPROP 2 LAST $XR0 13H11<> 
J 0
(-12240 8100);
DISPLAY 0.638298 (-12240 8100);
PAINT MONO (-12240 8100);
FORCEPROP 2 LAST CDS_LIB cls
J 0
(-12300 8100);
DISPLAY INVISIBLE (-12300 8100);
FORCEPROP 1 LAST CDS_LMAN_SYM_OUTLINE -50,50,50,-50
J 0
(-12300 8100);
DISPLAY 0.468085 (-12300 8100);
PAINT GREEN (-12300 8100);
DISPLAY INVISIBLE (-12300 8100);
FORCEPROP 1 LAST BODY_TYPE COMMENT
J 0
(-12290 7927);
DISPLAY 0.808511 (-12290 7927);
PAINT GREEN (-12290 7927);
DISPLAY INVISIBLE (-12290 7927);
FORCEPROP 1 LAST OFFPAGE TRUE
J 0
(-12290 8007);
DISPLAY 0.808511 (-12290 8007);
PAINT GREEN (-12290 8007);
DISPLAY INVISIBLE (-12290 8007);
FORCEPROP 2 LAST PATH I913
J 0
(-12200 8150);
DISPLAY 1.021277 (-12200 8150);
DISPLAY INVISIBLE (-12200 8150);
FORCEADD OFFPAGE_BI..1
R 6
(-12300 8300);
FORCEPROP 2 LAST $XR0 13H11<> 
J 0
(-12240 8300);
DISPLAY 0.638298 (-12240 8300);
PAINT MONO (-12240 8300);
FORCEPROP 1 LAST BODY_TYPE COMMENT
J 0
(-12290 8127);
DISPLAY 0.808511 (-12290 8127);
PAINT GREEN (-12290 8127);
DISPLAY INVISIBLE (-12290 8127);
FORCEPROP 1 LAST CDS_LMAN_SYM_OUTLINE -50,50,50,-50
J 0
(-12300 8300);
DISPLAY 0.468085 (-12300 8300);
PAINT GREEN (-12300 8300);
DISPLAY INVISIBLE (-12300 8300);
FORCEPROP 2 LAST CDS_LIB cls
J 0
(-12300 8300);
DISPLAY INVISIBLE (-12300 8300);
FORCEPROP 1 LAST OFFPAGE TRUE
J 0
(-12290 8207);
DISPLAY 0.808511 (-12290 8207);
PAINT GREEN (-12290 8207);
DISPLAY INVISIBLE (-12290 8207);
FORCEPROP 2 LAST PATH I915
J 0
(-12200 8350);
DISPLAY 1.021277 (-12200 8350);
DISPLAY INVISIBLE (-12200 8350);
FORCEADD SHEET_A1..1
(700 200);
FORCEPROP 2 LAST CUSTOM_TXT_CDS <XR_PAGE_TITLE>
J 0
(-14870 11550);
DISPLAY 0.638298 (-14870 11550);
PAINT PINK (-14870 11550);
FORCEPROP 1 LAST CUSTOM_TXT_CDS <DOCNO>
J 0
(-1350 585);
DISPLAY 0.978723 (-1350 585);
FORCEPROP 1 LAST CUSTOM_TXT_CDS <CON_PAGE_NUM>
J 0
(-1455 250);
DISPLAY 0.978723 (-1455 250);
FORCEPROP 1 LAST CUSTOM_TXT_CDS <DATE>
J 0
(0 375);
DISPLAY 0.978723 (0 375);
FORCEPROP 1 LAST CUSTOM_TXT_CDS <TITLE>
J 1
(-1085 830);
DISPLAY 0.978723 (-1085 830);
FORCEPROP 1 LAST CUSTOM_TXT_CDS <DESIGNER>
J 0
(0 800);
DISPLAY 0.978723 (0 800);
FORCEPROP 1 LAST CUSTOM_TXT_CDS <CON_TOTAL_PAGES>
J 0
(-1145 250);
DISPLAY 0.808511 (-1145 250);
FORCEPROP 1 LAST CUSTOM_TXT_CDS <ASSY_PN>
J 0
(-1350 375);
DISPLAY 0.978723 (-1350 375);
FORCEPROP 1 LAST CUSTOM_TXT_CDS <DOCREV>
J 0
(0 575);
DISPLAY 0.978723 (0 575);
FORCEPROP 1 LAST TITLE TEST_POINT&PMOD_CONN
J 0
(-2250 1100);
DISPLAY 3.042553 (-2250 1100);
PAINT GREEN (-2250 1100);
FORCEPROP 2 LAST CDS_XR_PAGE_TITLE CR-25 : @TIMECARD_LIB.TIMECARD(SCH_1):PAGE25
J 0
(-14870 11550);
DISPLAY 0.638298 (-14870 11550);
PAINT PINK (-14870 11550);
DISPLAY INVISIBLE (-14870 11550);
FORCEPROP 1 LAST COMMENT_BODY TRUE
J 0
(710 255);
DISPLAY 0.808511 (710 255);
DISPLAY INVISIBLE (710 255);
FORCEPROP 2 LAST CDS_LIB cls
J 0
(700 200);
DISPLAY INVISIBLE (700 200);
FORCEPROP 1 LAST CDS_LMAN_SYM_OUTLINE -15850,11500,200,-200
J 0
(700 200);
DISPLAY 0.468085 (700 200);
PAINT GREEN (700 200);
DISPLAY INVISIBLE (700 200);
FORCEPROP 2 LAST PAGE_BORDER TRUE
J 0
(-14870 11550);
DISPLAY 0.638298 (-14870 11550);
PAINT PINK (-14870 11550);
DISPLAY INVISIBLE (-14870 11550);
WIRE 16 -1 (-10850 9400)(-9650 9400);
FORCEPROP 2 LAST SIG_NAME MUX3_SEL
J 0
(-10710 9410);
DISPLAY 1.021277 (-10710 9410);
WIRE 16 -1 (-10850 9200)(-9650 9200);
FORCEPROP 2 LAST SIG_NAME MUX1_SEL
J 0
(-10710 9210);
DISPLAY 1.021277 (-10710 9210);
WIRE 16 -1 (-10850 8950)(-9650 8950);
FORCEPROP 2 LAST SIG_NAME R_BNO080_RST_N
J 0
(-10710 8960);
DISPLAY 1.021277 (-10710 8960);
WIRE 16 -1 (-10850 8850)(-9650 8850);
FORCEPROP 2 LAST SIG_NAME R_BNO080_INT_N
J 0
(-10710 8860);
DISPLAY 1.021277 (-10710 8860);
WIRE 16 -1 (-10850 8750)(-9650 8750);
FORCEPROP 2 LAST SIG_NAME R_BNO080_BOOT_N
J 0
(-10710 8760);
DISPLAY 1.021277 (-10710 8760);
WIRE 16 -1 (-10850 8650)(-9650 8650);
FORCEPROP 2 LAST SIG_NAME SN_EEPROM_WP
J 0
(-10710 8660);
DISPLAY 1.021277 (-10710 8660);
WIRE 16 -1 (-10850 8550)(-9650 8550);
FORCEPROP 2 LAST SIG_NAME SEC_EEPROM_WP
J 0
(-10710 8560);
DISPLAY 1.021277 (-10710 8560);
WIRE 16 -1 (-10850 8350)(-9650 8350);
FORCEPROP 2 LAST SIG_NAME PCA9546_RST_N
J 0
(-10710 8360);
DISPLAY 1.021277 (-10710 8360);
WIRE 16 -1 (-10850 8250)(-9650 8250);
FORCEPROP 2 LAST SIG_NAME FPGA_IN_LM75B_INT3_N
J 0
(-10710 8260);
DISPLAY 1.021277 (-10710 8260);
WIRE 16 -1 (-13200 9300)(-12350 9300);
FORCEPROP 2 LAST SIG_NAME IO_L21P_16
J 0
(-12910 9310);
DISPLAY 1.021277 (-12910 9310);
WIRE 16 -1 (-13200 9050)(-12350 9050);
FORCEPROP 2 LAST SIG_NAME IO_L22P_16
J 0
(-12910 9060);
DISPLAY 1.021277 (-12910 9060);
WIRE 16 -1 (-13200 8950)(-12350 8950);
FORCEPROP 2 LAST SIG_NAME IO_L22N_16
J 0
(-12910 8960);
DISPLAY 1.021277 (-12910 8960);
WIRE 16 -1 (-13200 8850)(-12350 8850);
FORCEPROP 2 LAST SIG_NAME IO_L23P_16
J 0
(-12910 8860);
DISPLAY 1.021277 (-12910 8860);
WIRE 16 -1 (-13200 8750)(-12350 8750);
FORCEPROP 2 LAST SIG_NAME IO_L23N_16
J 0
(-12910 8760);
DISPLAY 1.021277 (-12910 8760);
WIRE 16 -1 (-13200 8550)(-12350 8550);
FORCEPROP 2 LAST SIG_NAME IO_L24N_16
J 0
(-12910 8560);
DISPLAY 1.021277 (-12910 8560);
WIRE 16 -1 (-13200 8300)(-12350 8300);
FORCEPROP 2 LAST SIG_NAME IO_L20P_34
J 0
(-12910 8310);
DISPLAY 1.021277 (-12910 8310);
WIRE 16 -1 (-10850 5900)(-9650 5900);
FORCEPROP 2 LAST SIG_NAME XP1R2V_FPGA_PG
J 0
(-10710 5910);
DISPLAY 1.021277 (-10710 5910);
WIRE 16 -1 (-10850 5800)(-9650 5800);
FORCEPROP 2 LAST SIG_NAME XP1R8V_FPGA_PG
J 0
(-10710 5810);
DISPLAY 1.021277 (-10710 5810);
WIRE 16 -1 (-10850 8150)(-9650 8150);
FORCEPROP 2 LAST SIG_NAME FPGA_IN_LM75B_INT2_N
J 0
(-10710 8160);
DISPLAY 1.021277 (-10710 8160);
WIRE 16 -1 (-10850 8050)(-9650 8050);
FORCEPROP 2 LAST SIG_NAME FPGA_IN_LM75B_INT1_N
J 0
(-10710 8060);
DISPLAY 1.021277 (-10710 8060);
WIRE 16 -1 (-10850 7900)(-9650 7900);
FORCEPROP 2 LAST SIG_NAME RGB_LED_SHUTDOWN_N
J 0
(-10710 7910);
DISPLAY 1.021277 (-10710 7910);
WIRE 16 -1 (-10850 7700)(-9650 7700);
FORCEPROP 2 LAST SIG_NAME R_SHT3X_RST_N
J 0
(-10710 7710);
DISPLAY 1.021277 (-10710 7710);
WIRE 16 -1 (-10850 7600)(-9650 7600);
FORCEPROP 2 LAST SIG_NAME R_SHT3X_ALERT_N
J 0
(-10710 7610);
DISPLAY 1.021277 (-10710 7610);
WIRE 16 -1 (-10850 7450)(-9650 7450);
FORCEPROP 2 LAST SIG_NAME SMA1_SIG_IN_BF_EN_N
J 0
(-10710 7460);
DISPLAY 1.021277 (-10710 7460);
WIRE 16 -1 (-10850 7250)(-9650 7250);
FORCEPROP 2 LAST SIG_NAME SMA3_SIG_IN_BF_EN_N
J 0
(-10710 7260);
DISPLAY 1.021277 (-10710 7260);
WIRE 16 -1 (-10850 7000)(-9650 7000);
FORCEPROP 2 LAST SIG_NAME SMA1_SIG_OUT_BF_EN_N
J 0
(-10710 7010);
DISPLAY 1.021277 (-10710 7010);
WIRE 16 -1 (-10850 6800)(-9650 6800);
FORCEPROP 2 LAST SIG_NAME SMA3_SIG_OUT_BF_EN_N
J 0
(-10710 6810);
DISPLAY 1.021277 (-10710 6810);
WIRE 16 -1 (-10850 6700)(-9650 6700);
FORCEPROP 2 LAST SIG_NAME SMA4_SIG_OUT_BF_EN_N
J 0
(-10710 6710);
DISPLAY 1.021277 (-10710 6710);
WIRE 16 -1 (-10850 6400)(-9650 6400);
FORCEPROP 2 LAST SIG_NAME XP12R0V_A_PG
J 0
(-10710 6410);
DISPLAY 1.021277 (-10710 6410);
WIRE 16 -1 (-10850 6200)(-9650 6200);
FORCEPROP 2 LAST SIG_NAME XP3R3V_EN
J 0
(-10710 6210);
DISPLAY 1.021277 (-10710 6210);
WIRE 16 -1 (-10850 6100)(-9650 6100);
FORCEPROP 2 LAST SIG_NAME XP3R3V_PG
J 0
(-10710 6110);
DISPLAY 1.021277 (-10710 6110);
WIRE 16 -1 (-10850 6000)(-9650 6000);
FORCEPROP 2 LAST SIG_NAME XP1R0V_FPGA_PG
J 0
(-10710 6010);
DISPLAY 1.021277 (-10710 6010);
WIRE 16 -1 (-13200 8200)(-12350 8200);
FORCEPROP 2 LAST SIG_NAME IO_L20N_34
J 0
(-12910 8210);
DISPLAY 1.021277 (-12910 8210);
WIRE 16 -1 (-13200 8100)(-12350 8100);
FORCEPROP 2 LAST SIG_NAME IO_L21P_34
J 0
(-12910 8110);
DISPLAY 1.021277 (-12910 8110);
WIRE 16 -1 (-13200 8000)(-12350 8000);
FORCEPROP 2 LAST SIG_NAME IO_L21N_34
J 0
(-12910 8010);
DISPLAY 1.021277 (-12910 8010);
WIRE 16 -1 (-13200 7900)(-12350 7900);
FORCEPROP 2 LAST SIG_NAME IO_L22P_34
J 0
(-12910 7910);
DISPLAY 1.021277 (-12910 7910);
WIRE 16 -1 (-13200 7800)(-12350 7800);
FORCEPROP 2 LAST SIG_NAME IO_L22N_34
J 0
(-12910 7810);
DISPLAY 1.021277 (-12910 7810);
WIRE 16 -1 (-13200 7700)(-12350 7700);
FORCEPROP 2 LAST SIG_NAME IO_L23P_34
J 0
(-12910 7710);
DISPLAY 1.021277 (-12910 7710);
WIRE 16 -1 (-13200 7600)(-12350 7600);
FORCEPROP 2 LAST SIG_NAME IO_L23N_34
J 0
(-12910 7610);
DISPLAY 1.021277 (-12910 7610);
WIRE 16 -1 (-13200 7500)(-12350 7500);
FORCEPROP 2 LAST SIG_NAME IO_L24P_34
J 0
(-12910 7510);
DISPLAY 1.021277 (-12910 7510);
WIRE 16 -1 (-13200 7400)(-12350 7400);
FORCEPROP 2 LAST SIG_NAME IO_L24N_34
J 0
(-12910 7410);
DISPLAY 1.021277 (-12910 7410);
WIRE 16 -1 (-13250 6750)(-12450 6750);
FORCEPROP 2 LAST SIG_NAME IO_L20P_35
J 0
(-13210 6760);
DISPLAY 1.021277 (-13210 6760);
WIRE 16 -1 (-13250 6650)(-12450 6650);
FORCEPROP 2 LAST SIG_NAME IO_L20N_35
J 0
(-13210 6660);
DISPLAY 1.021277 (-13210 6660);
WIRE 16 -1 (-13250 6550)(-12450 6550);
FORCEPROP 2 LAST SIG_NAME IO_L21P_35
J 0
(-13210 6560);
DISPLAY 1.021277 (-13210 6560);
WIRE 16 -1 (-13250 6450)(-12450 6450);
FORCEPROP 2 LAST SIG_NAME IO_L21N_35
J 0
(-13210 6460);
DISPLAY 1.021277 (-13210 6460);
WIRE 16 -1 (-13250 6350)(-12450 6350);
FORCEPROP 2 LAST SIG_NAME IO_L22P_35
J 0
(-13210 6360);
DISPLAY 1.021277 (-13210 6360);
WIRE 16 -1 (-13250 6250)(-12450 6250);
FORCEPROP 2 LAST SIG_NAME IO_L22N_35
J 0
(-13210 6260);
DISPLAY 1.021277 (-13210 6260);
WIRE 16 -1 (-13250 6150)(-12450 6150);
FORCEPROP 2 LAST SIG_NAME IO_L23P_35
J 0
(-13210 6160);
DISPLAY 1.021277 (-13210 6160);
WIRE 16 -1 (-13250 5950)(-12450 5950);
FORCEPROP 2 LAST SIG_NAME IO_L24P_35
J 0
(-13210 5960);
DISPLAY 1.021277 (-13210 5960);
WIRE 16 -1 (-13250 5850)(-12450 5850);
FORCEPROP 2 LAST SIG_NAME IO_L24N_35
J 0
(-13210 5860);
DISPLAY 1.021277 (-13210 5860);
WIRE 16 -1 (-10850 6300)(-9650 6300);
FORCEPROP 2 LAST SIG_NAME XP12R0V_A_FLTB
J 0
(-10710 6310);
DISPLAY 1.021277 (-10710 6310);
WIRE 16 -1 (-8150 9400)(-6950 9400);
FORCEPROP 2 LAST SIG_NAME FPGA_PROGRAM_N
J 0
(-7960 9410);
DISPLAY 1.021277 (-7960 9410);
WIRE 16 -1 (-8150 8400)(-6950 8400);
FORCEPROP 2 LAST SIG_NAME R_MAC_BITE OUT
J 0
(-7960 8410);
DISPLAY 1.021277 (-7960 8410);
WIRE 16 -1 (-8150 8750)(-6950 8750);
FORCEPROP 2 LAST SIG_NAME CLK_125M_OE
J 0
(-7960 8760);
DISPLAY 1.021277 (-7960 8760);
WIRE 16 -1 (-8150 8500)(-6950 8500);
FORCEPROP 2 LAST SIG_NAME MAC_ALARM
J 0
(-7960 8510);
DISPLAY 1.021277 (-7960 8510);
WIRE 16 -1 (-8150 9200)(-6950 9200);
FORCEPROP 2 LAST SIG_NAME FPGA_MGTRREF
J 0
(-7960 9210);
DISPLAY 1.021277 (-7960 9210);
WIRE 16 -1 (-10850 3800)(-11550 3800);
FORCEPROP 2 LAST SIG_NAME FPGA_IO_1
J 0
(-11310 3810);
DISPLAY 1.021277 (-11310 3810);
WIRE 16 -1 (-11550 3800)(-11550 3700);
WIRE 16 -1 (-12200 3800)(-11550 3800);
WIRE 16 -1 (-12200 3700)(-11550 3700);
WIRE 16 -1 (-10850 3500)(-11550 3500);
FORCEPROP 2 LAST SIG_NAME FPGA_IO_2
J 0
(-11310 3510);
DISPLAY 1.021277 (-11310 3510);
WIRE 16 -1 (-11550 3500)(-11550 3400);
WIRE 16 -1 (-12200 3500)(-11550 3500);
WIRE 16 -1 (-12200 3400)(-11550 3400);
WIRE 16 -1 (-10850 2300)(-11550 2300);
FORCEPROP 2 LAST SIG_NAME FPGA_IO_6
J 0
(-11310 2310);
DISPLAY 1.021277 (-11310 2310);
WIRE 16 -1 (-11550 2300)(-11550 2200);
WIRE 16 -1 (-12200 2300)(-11550 2300);
WIRE 16 -1 (-12200 2200)(-11550 2200);
WIRE 16 -1 (-10850 2000)(-11550 2000);
FORCEPROP 2 LAST SIG_NAME FPGA_IO_7
J 0
(-11310 2010);
DISPLAY 1.021277 (-11310 2010);
WIRE 16 -1 (-11550 2000)(-11550 1900);
WIRE 16 -1 (-12200 2000)(-11550 2000);
WIRE 16 -1 (-12200 1900)(-11550 1900);
WIRE 16 -1 (-13250 6050)(-12450 6050);
FORCEPROP 2 LAST SIG_NAME IO_L23N_35
J 0
(-13210 6060);
DISPLAY 1.021277 (-13210 6060);
WIRE 16 -1 (-10850 6900)(-9650 6900);
FORCEPROP 2 LAST SIG_NAME SMA2_SIG_OUT_BF_EN_N
J 0
(-10710 6910);
DISPLAY 1.021277 (-10710 6910);
WIRE 16 -1 (-10850 9050)(-9650 9050);
FORCEPROP 2 LAST SIG_NAME GPS_RST_N
J 0
(-10710 9060);
DISPLAY 1.021277 (-10710 9060);
WIRE 16 -1 (-10850 9300)(-9650 9300);
FORCEPROP 2 LAST SIG_NAME MUX2_SEL
J 0
(-10710 9310);
DISPLAY 1.021277 (-10710 9310);
WIRE 16 -1 (-10850 9500)(-9650 9500);
FORCEPROP 2 LAST SIG_NAME FT_USB_DETECT
J 0
(-10710 9510);
DISPLAY 1.021277 (-10710 9510);
WIRE 16 -1 (-13200 9500)(-12350 9500);
FORCEPROP 2 LAST SIG_NAME IO_L20P_16
J 0
(-12910 9510);
DISPLAY 1.021277 (-12910 9510);
WIRE 16 -1 (-13200 9400)(-12350 9400);
FORCEPROP 2 LAST SIG_NAME IO_L20N_16
J 0
(-12910 9410);
DISPLAY 1.021277 (-12910 9410);
WIRE 16 -1 (-13200 8650)(-12350 8650);
FORCEPROP 2 LAST SIG_NAME IO_L24P_16
J 0
(-12910 8660);
DISPLAY 1.021277 (-12910 8660);
WIRE 16 -1 (-10850 7150)(-9650 7150);
FORCEPROP 2 LAST SIG_NAME SMA4_SIG_IN_BF_EN_N
J 0
(-10710 7160);
DISPLAY 1.021277 (-10710 7160);
WIRE 16 -1 (-10850 6500)(-9650 6500);
FORCEPROP 2 LAST SIG_NAME XP12R0V_A_EN
J 0
(-10710 6510);
DISPLAY 1.021277 (-10710 6510);
WIRE 16 -1 (-13200 9200)(-12350 9200);
FORCEPROP 2 LAST SIG_NAME IO_L21N_16
J 0
(-12910 9210);
DISPLAY 1.021277 (-12910 9210);
WIRE 16 -1 (-10850 7350)(-9650 7350);
FORCEPROP 2 LAST SIG_NAME SMA2_SIG_IN_BF_EN_N
J 0
(-10710 7360);
DISPLAY 1.021277 (-10710 7360);
WIRE 16 -1 (-8150 8850)(-6950 8850);
FORCEPROP 2 LAST SIG_NAME CLK_200M_OE
J 0
(-7960 8860);
DISPLAY 1.021277 (-7960 8860);
WIRE 16 -1 (-8150 9000)(-6950 9000);
FORCEPROP 2 LAST SIG_NAME PCIE_CONN_PERST_N
J 0
(-7960 9010);
DISPLAY 1.021277 (-7960 9010);
WIRE 16 -1 (-8150 9500)(-6950 9500);
FORCEPROP 2 LAST SIG_NAME FPGA_DONE
J 0
(-7960 9510);
DISPLAY 1.021277 (-7960 9510);
WIRE 16 -1 (-10850 3200)(-11550 3200);
FORCEPROP 2 LAST SIG_NAME FPGA_IO_3
J 0
(-11310 3210);
DISPLAY 1.021277 (-11310 3210);
WIRE 16 -1 (-11550 3200)(-11550 3100);
WIRE 16 -1 (-12200 3200)(-11550 3200);
WIRE 16 -1 (-12200 3100)(-11550 3100);
WIRE 16 -1 (-10850 2600)(-11550 2600);
FORCEPROP 2 LAST SIG_NAME FPGA_IO_5
J 0
(-11310 2610);
DISPLAY 1.021277 (-11310 2610);
WIRE 16 -1 (-11550 2600)(-11550 2500);
WIRE 16 -1 (-12200 2600)(-11550 2600);
WIRE 16 -1 (-12200 2500)(-11550 2500);
WIRE 16 -1 (-10850 2900)(-11550 2900);
FORCEPROP 2 LAST SIG_NAME FPGA_IO_4
J 0
(-11310 2910);
DISPLAY 1.021277 (-11310 2910);
WIRE 16 -1 (-11550 2900)(-11550 2800);
WIRE 16 -1 (-12200 2900)(-11550 2900);
WIRE 16 -1 (-12200 2800)(-11550 2800);
WIRE 16 -1 (-12200 4100)(-11550 4100);
WIRE 16 -1 (-10850 4100)(-11550 4100);
FORCEPROP 2 LAST SIG_NAME FPGA_IO_0
J 0
(-11310 4110);
DISPLAY 1.021277 (-11310 4110);
WIRE 16 -1 (-11550 4100)(-11550 4000);
WIRE 16 -1 (-12200 4000)(-11550 4000);
WIRE 16 273 (-14200 5100)(200 5100);
WIRE 16 -1 (-3850 3250)(-4950 3250);
FORCEPROP 2 LAST SIG_NAME FPGA_IO_3
J 0
(-4310 3260);
DISPLAY 1.021277 (-4310 3260);
WIRE 16 -1 (-5800 3250)(-5200 3250);
WIRE 16 -1 (-3850 3150)(-4950 3150);
FORCEPROP 2 LAST SIG_NAME FPGA_IO_2
J 0
(-4310 3160);
DISPLAY 1.021277 (-4310 3160);
WIRE 16 -1 (-5800 3150)(-5200 3150);
WIRE 16 -1 (-3850 3050)(-4950 3050);
FORCEPROP 2 LAST SIG_NAME FPGA_IO_1
J 0
(-4310 3060);
DISPLAY 1.021277 (-4310 3060);
WIRE 16 -1 (-5800 3050)(-5200 3050);
WIRE 16 -1 (-3850 2950)(-4950 2950);
FORCEPROP 2 LAST SIG_NAME FPGA_IO_0
J 0
(-4310 2960);
DISPLAY 1.021277 (-4310 2960);
WIRE 16 -1 (-5800 2950)(-5200 2950);
WIRE 16 -1 (-6400 3250)(-7000 3250);
WIRE 16 -1 (-6400 3150)(-7000 3150);
WIRE 16 -1 (-6400 3050)(-7000 3050);
WIRE 16 -1 (-6400 2950)(-7000 2950);
WIRE 16 -1 (-7250 3250)(-8350 3250);
FORCEPROP 2 LAST SIG_NAME FPGA_IO_7
J 0
(-8310 3260);
DISPLAY 1.021277 (-8310 3260);
WIRE 16 -1 (-7250 3150)(-8350 3150);
FORCEPROP 2 LAST SIG_NAME FPGA_IO_6
J 0
(-8310 3160);
DISPLAY 1.021277 (-8310 3160);
WIRE 16 -1 (-7250 3050)(-8350 3050);
FORCEPROP 2 LAST SIG_NAME FPGA_IO_5
J 0
(-8310 3060);
DISPLAY 1.021277 (-8310 3060);
WIRE 16 -1 (-7250 2950)(-8350 2950);
FORCEPROP 2 LAST SIG_NAME FPGA_IO_4
J 0
(-8310 2960);
DISPLAY 1.021277 (-8310 2960);
WIRE 16 -1 (-12850 1900)(-12850 2200);
WIRE 16 -1 (-12450 1900)(-12850 1900);
WIRE 16 -1 (-12850 1900)(-12850 1700);
WIRE 16 -1 (-12450 2200)(-12850 2200);
WIRE 16 -1 (-12850 2200)(-12850 2500);
WIRE 16 -1 (-12450 2500)(-12850 2500);
WIRE 16 -1 (-12850 2500)(-12850 2800);
WIRE 16 -1 (-12850 2800)(-12850 3100);
WIRE 16 -1 (-12450 2800)(-12850 2800);
WIRE 16 -1 (-12450 3100)(-12850 3100);
WIRE 16 -1 (-12850 3100)(-12850 3400);
WIRE 16 -1 (-12450 3400)(-12850 3400);
WIRE 16 -1 (-12850 3700)(-12850 3400);
WIRE 16 -1 (-12450 3700)(-12850 3700);
WIRE 16 -1 (-12850 3700)(-12850 4000);
WIRE 16 -1 (-12450 4000)(-12850 4000);
WIRE 16 -1 (-12450 4100)(-12950 4100);
WIRE 16 -1 (-12950 4100)(-12950 4250);
WIRE 16 -1 (-12950 4100)(-12950 3800);
WIRE 16 -1 (-12450 3800)(-12950 3800);
WIRE 16 -1 (-12950 3800)(-12950 3500);
WIRE 16 -1 (-12450 3500)(-12950 3500);
WIRE 16 -1 (-12950 3500)(-12950 3200);
WIRE 16 -1 (-12450 3200)(-12950 3200);
WIRE 16 -1 (-12950 3200)(-12950 2900);
WIRE 16 -1 (-12450 2900)(-12950 2900);
WIRE 16 -1 (-12950 2900)(-12950 2600);
WIRE 16 -1 (-12450 2600)(-12950 2600);
WIRE 16 -1 (-12950 2600)(-12950 2300);
WIRE 16 -1 (-12450 2300)(-12950 2300);
WIRE 16 -1 (-12950 2300)(-12950 2000);
WIRE 16 -1 (-12450 2000)(-12950 2000);
WIRE 16 -1 (-3400 7350)(-4250 7350);
WIRE 16 -1 (-4250 7450)(-4250 7350);
WIRE 16 -1 (-1950 9300)(-1950 9200);
WIRE 16 -1 (-1950 9200)(-1100 9200);
WIRE 16 -1 (-5750 3650)(-5750 3450);
WIRE 16 -1 (-6450 3650)(-5750 3650);
WIRE 16 -1 (-5750 3450)(-5800 3450);
WIRE 16 -1 (-6450 3650)(-6450 3450);
WIRE 16 -1 (-6450 3750)(-6450 3650);
WIRE 16 -1 (-6450 3450)(-6400 3450);
WIRE 16 -1 (-1100 8800)(-1950 8800);
WIRE 16 -1 (-1950 8800)(-1950 8850);
WIRE 16 -1 (-1100 8350)(-1950 8350);
WIRE 16 -1 (-1950 8350)(-1950 8400);
WIRE 16 -1 (-1100 7900)(-1950 7900);
WIRE 16 -1 (-1950 7900)(-1950 8000);
WIRE 16 -1 (-1100 7450)(-1950 7450);
WIRE 16 -1 (-1950 7450)(-1950 7550);
WIRE 16 -1 (-1100 7000)(-1950 7000);
WIRE 16 -1 (-1950 7000)(-1950 7100);
WIRE 16 -1 (-3400 9150)(-4250 9150);
WIRE 16 -1 (-4250 9150)(-4250 9250);
WIRE 16 -1 (-3400 8700)(-4250 8700);
WIRE 16 -1 (-4250 8700)(-4250 8800);
WIRE 16 -1 (-3400 8250)(-4250 8250);
WIRE 16 -1 (-4250 8250)(-4250 8350);
WIRE 16 -1 (-3400 7800)(-4250 7800);
WIRE 16 -1 (-4250 7800)(-4250 7900);
WIRE 16 -1 (-6400 3350)(-6450 3350);
WIRE 16 -1 (-6450 3350)(-6450 2750);
WIRE 16 -1 (-5800 3350)(-5750 3350);
WIRE 16 -1 (-5750 3350)(-5750 2750);
WIRE 16 -1 (-8150 9300)(-6950 9300);
FORCEPROP 2 LAST SIG_NAME FPGA_CFG_INIT_N
J 0
(-7960 9310);
DISPLAY 1.021277 (-7960 9310);
DOT 1 (-12850 2200);
DOT 1 (-11550 4100);
DOT 1 (-11550 3800);
DOT 1 (-11550 3500);
DOT 1 (-11550 3200);
DOT 1 (-11550 2900);
DOT 1 (-11550 2600);
DOT 1 (-11550 2300);
DOT 1 (-11550 2000);
DOT 1 (-12950 4100);
DOT 1 (-12950 3800);
DOT 1 (-12850 3700);
DOT 1 (-12950 3500);
DOT 1 (-12850 3400);
DOT 1 (-12950 3200);
DOT 1 (-12850 3100);
DOT 1 (-12950 2900);
DOT 1 (-12850 2800);
DOT 1 (-12950 2600);
DOT 1 (-12850 2500);
DOT 1 (-12950 2300);
DOT 1 (-12850 1900);
DOT 1 (-6450 3650);
FORCENOTE
PLACE ALL TEST POINTS AT THE BOTTOM SIDE OF THE PCB
(-7350 6000) 0;
DISPLAY LEFT (-7350 6000);
DISPLAY 2.510638 (-7350 6000);
FORCENOTE
TEST POINT
(-7950 10500) 0;
DISPLAY LEFT (-7950 10500);
DISPLAY 3.936170 (-7950 10500);
FORCENOTE
PMOD CONN
(-6700 4200) 0;
DISPLAY LEFT (-6700 4200);
DISPLAY 3.148936 (-6700 4200);
QUIT
